FILE_TYPE = MACRO_DRAWING;
SET COLOR_WIRE YELLOW;
SET COLOR_PROP ORANGE;
SET COLOR_DOT WHITE;
SET COLOR_ARC YELLOW;
SET COLOR_BODY GREEN;
SET COLOR_NOTE PURPLE;
SET PROP_DISPLAY VALUE;
SET PAGE_NUMBER P44;
SET PATH_NUMBER P366;
FORCEADD OFFPAGE..1
(-300 650);
FORCEPROP 2 LAST $XR1 44 
J 0
(-611 650);
DISPLAY 0.638298 (-611 650);
PAINT MONO (-611 650);
FORCEPROP 2 LAST $XR0 13 
J 0
(-521 650);
DISPLAY 0.638298 (-521 650);
PAINT MONO (-521 650);
FORCEPROP 2 LAST CDS_LIB standard
J 0
(-300 650);
DISPLAY INVISIBLE (-300 650);
FORCEPROP 1 LAST OFFPAGE TRUE
J 0
(25 525);
DISPLAY 0.872340 (25 525);
PAINT GREEN (25 525);
DISPLAY INVISIBLE (25 525);
FORCEPROP 1 LAST COMMENT_BODY TRUE
J 0
(-175 550);
DISPLAY 0.872340 (-175 550);
PAINT PEACH (-175 550);
DISPLAY INVISIBLE (-175 550);
FORCEPROP 2 LAST PATH I262
J 0
(-500 700);
DISPLAY 1.021277 (-500 700);
DISPLAY INVISIBLE (-500 700);
FORCEADD OFFPAGE..1
(-300 750);
FORCEPROP 2 LAST $XR0 44 
J 0
(-521 750);
DISPLAY 0.638298 (-521 750);
PAINT MONO (-521 750);
FORCEPROP 2 LAST CDS_LIB standard
J 0
(-300 750);
DISPLAY INVISIBLE (-300 750);
FORCEPROP 1 LAST OFFPAGE TRUE
J 0
(25 625);
DISPLAY 0.872340 (25 625);
PAINT GREEN (25 625);
DISPLAY INVISIBLE (25 625);
FORCEPROP 1 LAST COMMENT_BODY TRUE
J 0
(-175 650);
DISPLAY 0.872340 (-175 650);
PAINT PEACH (-175 650);
DISPLAY INVISIBLE (-175 650);
FORCEPROP 2 LAST PATH I263
J 0
(-500 800);
DISPLAY 1.021277 (-500 800);
DISPLAY INVISIBLE (-500 800);
FORCEADD IDTQS3VH257PAG..1
R 2
(2325 1050);
FORCEPROP 1 LAST PART_NUMBER AL000257K00
J 2
(2577 1560);
DISPLAY 0.510638 (2577 1560);
PAINT WHITE (2577 1560);
FORCEPROP 1 LAST VALUE IDTQS3VH257PAG
J 2
(2577 1720);
DISPLAY 0.510638 (2577 1720);
PAINT SKYBLUE (2577 1720);
FORCEPROP 1 LAST MATERIAL IC
J 2
(2577 1480);
DISPLAY 0.510638 (2577 1480);
PAINT SKYBLUE (2577 1480);
FORCEPROP 2 LAST SEC_TYPE SMLF
J 0
(2600 1800);
DISPLAY 1.021277 (2600 1800);
DISPLAY INVISIBLE (2600 1800);
FORCEPROP 1 LAST PACK_TYPE SMLF
J 2
(2475 400);
DISPLAY 0.510638 (2475 400);
PAINT SKYBLUE (2475 400);
DISPLAY INVISIBLE (2475 400);
FORCEPROP 0 LAST MANUF_PN IDTQS3VH257PAG
J 2
(2575 1825);
DISPLAY 1.021277 (2575 1825);
DISPLAY INVISIBLE (2575 1825);
FORCEPROP 2 LAST CDS_LIB pure_quanta
J 2
(2325 1050);
DISPLAY INVISIBLE (2325 1050);
FORCEPROP 1 LAST CDS_LMAN_SYM_OUTLINE -250,400,250,-500
J 2
(2475 1000);
DISPLAY 0.468085 (2475 1000);
PAINT GREEN (2475 1000);
DISPLAY INVISIBLE (2475 1000);
FORCEPROP 0 LAST PATH I271
J 0
(2600 1750);
DISPLAY 1.021277 (2600 1750);
DISPLAY INVISIBLE (2600 1750);
FORCEPROP 1 LAST LOCATION U30
J 2
(2577 1640);
DISPLAY 0.702128 (2577 1640);
PAINT AQUA (2577 1640);
FORCEPROP 1 LASTPIN (1925 650) $PN 15
J 2
(2035 653);
DISPLAY 0.808511 (2035 653);
PAINT WHITE (2035 653);
FORCEPROP 1 LASTPIN (2725 750) $PN 8
J 0
(2615 753);
DISPLAY 0.808511 (2615 753);
PAINT WHITE (2615 753);
FORCEPROP 1 LASTPIN (1925 1350) $PN 2
J 2
(2035 1353);
DISPLAY 0.808511 (2035 1353);
PAINT WHITE (2035 1353);
FORCEPROP 1 LASTPIN (1925 1200) $PN 5
J 2
(2035 1203);
DISPLAY 0.808511 (2035 1203);
PAINT WHITE (2035 1203);
FORCEPROP 1 LASTPIN (1925 1050) $PN 11
J 2
(2035 1053);
DISPLAY 0.808511 (2035 1053);
PAINT WHITE (2035 1053);
FORCEPROP 1 LASTPIN (1925 900) $PN 14
J 2
(2035 903);
DISPLAY 0.808511 (2035 903);
PAINT WHITE (2035 903);
FORCEPROP 1 LASTPIN (1925 1400) $PN 3
J 2
(2035 1403);
DISPLAY 0.808511 (2035 1403);
PAINT WHITE (2035 1403);
FORCEPROP 1 LASTPIN (1925 1250) $PN 6
J 2
(2035 1253);
DISPLAY 0.808511 (2035 1253);
PAINT WHITE (2035 1253);
FORCEPROP 1 LASTPIN (1925 1100) $PN 10
J 2
(2035 1103);
DISPLAY 0.808511 (2035 1103);
PAINT WHITE (2035 1103);
FORCEPROP 1 LASTPIN (1925 950) $PN 13
J 2
(2035 953);
DISPLAY 0.808511 (2035 953);
PAINT WHITE (2035 953);
FORCEPROP 1 LASTPIN (1925 750) $PN 1
J 2
(2035 753);
DISPLAY 0.808511 (2035 753);
PAINT WHITE (2035 753);
FORCEPROP 1 LASTPIN (2725 1350) $PN 16
J 0
(2615 1353);
DISPLAY 0.808511 (2615 1353);
PAINT WHITE (2615 1353);
FORCEPROP 1 LASTPIN (2725 1200) $PN 4
J 0
(2615 1203);
DISPLAY 0.808511 (2615 1203);
PAINT WHITE (2615 1203);
FORCEPROP 1 LASTPIN (2725 1100) $PN 7
J 0
(2615 1103);
DISPLAY 0.808511 (2615 1103);
PAINT WHITE (2615 1103);
FORCEPROP 1 LASTPIN (2725 1000) $PN 9
J 0
(2615 1003);
DISPLAY 0.808511 (2615 1003);
PAINT WHITE (2615 1003);
FORCEPROP 1 LASTPIN (2725 900) $PN 12
J 0
(2615 903);
DISPLAY 0.808511 (2615 903);
PAINT WHITE (2615 903);
FORCEPROP 0 LAST SEC 1
J 0
(2600 1750);
DISPLAY INVISIBLE (2600 1750);
FORCEADD UNIVERSAL_GND..1
(3275 600);
FORCEPROP 3 LASTPIN (3275 650) SIG_NAME GND\g
J 0
(3285 660);
DISPLAY 0.659574 (3285 660);
PAINT MONO (3285 660);
DISPLAY INVISIBLE (3285 660);
FORCEPROP 2 LAST CDS_LIB logical_power
J 0
(3275 600);
DISPLAY INVISIBLE (3275 600);
FORCEPROP 1 LAST HDL_POWER GND
J 1
(3259 566);
DISPLAY 0.702128 (3259 566);
PAINT GREEN (3259 566);
DISPLAY INVISIBLE (3259 566);
FORCEPROP 1 LAST PATH I272
J 0
(3350 600);
DISPLAY 0.872340 (3350 600);
PAINT AQUA (3350 600);
DISPLAY INVISIBLE (3350 600);
FORCEADD OFFPAGE..5
R 2
(4300 1000);
FORCEPROP 2 LAST $XR0 45 
J 0
(4489 1000);
DISPLAY 0.638298 (4489 1000);
PAINT MONO (4489 1000);
FORCEPROP 2 LAST CDS_LIB standard
J 0
(4300 1000);
DISPLAY INVISIBLE (4300 1000);
FORCEPROP 1 LAST OFFPAGE TRUE
J 2
(3975 875);
DISPLAY 0.872340 (3975 875);
PAINT GREEN (3975 875);
DISPLAY INVISIBLE (3975 875);
FORCEPROP 1 LAST COMMENT_BODY TRUE
J 2
(4200 925);
DISPLAY 0.872340 (4200 925);
PAINT PEACH (4200 925);
DISPLAY INVISIBLE (4200 925);
FORCEPROP 2 LAST PATH I273
J 0
(4600 1050);
DISPLAY 1.021277 (4600 1050);
DISPLAY INVISIBLE (4600 1050);
FORCEADD OFFPAGE..5
R 2
(4300 1100);
FORCEPROP 2 LAST $XR0 45 
J 0
(4489 1100);
DISPLAY 0.638298 (4489 1100);
PAINT MONO (4489 1100);
FORCEPROP 2 LAST CDS_LIB standard
J 0
(4300 1100);
DISPLAY INVISIBLE (4300 1100);
FORCEPROP 1 LAST OFFPAGE TRUE
J 2
(3975 975);
DISPLAY 0.872340 (3975 975);
PAINT GREEN (3975 975);
DISPLAY INVISIBLE (3975 975);
FORCEPROP 1 LAST COMMENT_BODY TRUE
J 2
(4200 1025);
DISPLAY 0.872340 (4200 1025);
PAINT PEACH (4200 1025);
DISPLAY INVISIBLE (4200 1025);
FORCEPROP 2 LAST PATH I274
J 0
(4600 1150);
DISPLAY 1.021277 (4600 1150);
DISPLAY INVISIBLE (4600 1150);
FORCEADD OFFPAGE..5
R 2
(4300 1200);
FORCEPROP 2 LAST $XR0 45 
J 0
(4489 1200);
DISPLAY 0.638298 (4489 1200);
PAINT MONO (4489 1200);
FORCEPROP 2 LAST CDS_LIB standard
J 0
(4300 1200);
DISPLAY INVISIBLE (4300 1200);
FORCEPROP 1 LAST OFFPAGE TRUE
J 2
(3975 1075);
DISPLAY 0.872340 (3975 1075);
PAINT GREEN (3975 1075);
DISPLAY INVISIBLE (3975 1075);
FORCEPROP 1 LAST COMMENT_BODY TRUE
J 2
(4200 1125);
DISPLAY 0.872340 (4200 1125);
PAINT PEACH (4200 1125);
DISPLAY INVISIBLE (4200 1125);
FORCEPROP 2 LAST PATH I275
J 0
(4600 1250);
DISPLAY 1.021277 (4600 1250);
DISPLAY INVISIBLE (4600 1250);
FORCEADD P3V3_AUX..1
(2925 1850);
FORCEPROP 3 LASTPIN (2925 1800) SIG_NAME P3V3_AUX\g
J 0
(2935 1810);
DISPLAY 0.659574 (2935 1810);
PAINT MONO (2935 1810);
DISPLAY INVISIBLE (2935 1810);
FORCEPROP 2 LAST CDS_LIB logical_power
J 0
(2925 1850);
DISPLAY INVISIBLE (2925 1850);
FORCEPROP 1 LAST SIZE 1B
J 0
(2970 1872);
DISPLAY 0.340426 (2970 1872);
PAINT GREEN (2970 1872);
DISPLAY INVISIBLE (2970 1872);
FORCEPROP 1 LAST BODY_TYPE PLUMBING
J 0
(2880 1807);
DISPLAY 0.340426 (2880 1807);
PAINT GREEN (2880 1807);
DISPLAY INVISIBLE (2880 1807);
FORCEPROP 1 LAST HDL_POWER P3V3_AUX
J 0
(2625 1725);
DISPLAY 0.702128 (2625 1725);
DISPLAY INVISIBLE (2625 1725);
FORCEPROP 1 LAST PATH I276
J 0
(2970 1852);
DISPLAY 0.340426 (2970 1852);
PAINT GREEN (2970 1852);
DISPLAY INVISIBLE (2970 1852);
FORCEADD UNIVERSAL_GND..1
R 2
(3100 1400);
FORCEPROP 3 LASTPIN (3100 1450) SIG_NAME GND\g
J 0
(3110 1460);
DISPLAY 0.659574 (3110 1460);
PAINT MONO (3110 1460);
DISPLAY INVISIBLE (3110 1460);
FORCEPROP 2 LAST CDS_LIB logical_power
J 0
(3100 1400);
DISPLAY INVISIBLE (3100 1400);
FORCEPROP 1 LAST HDL_POWER GND
J 1
(3075 1325);
DISPLAY 0.702128 (3075 1325);
PAINT GREEN (3075 1325);
DISPLAY INVISIBLE (3075 1325);
FORCEPROP 1 LAST PATH I277
J 2
(3025 1400);
DISPLAY 0.872340 (3025 1400);
PAINT AQUA (3025 1400);
DISPLAY INVISIBLE (3025 1400);
FORCEADD Q_CAP..1
(3100 1600);
FORCEPROP 1 LAST VOLTAGE 25V
J 0
(3150 1600);
DISPLAY 0.510638 (3150 1600);
PAINT SKYBLUE (3150 1600);
FORCEPROP 1 LAST PACK_TYPE 0402
J 0
(3150 1400);
DISPLAY 0.510638 (3150 1400);
PAINT SKYBLUE (3150 1400);
FORCEPROP 1 LAST TOLERANCE 10%
J 0
(3150 1550);
DISPLAY 0.510638 (3150 1550);
PAINT SKYBLUE (3150 1550);
FORCEPROP 1 LAST VALUE 0.1UF
J 0
(3150 1650);
DISPLAY 0.510638 (3150 1650);
PAINT SKYBLUE (3150 1650);
FORCEPROP 1 LAST PART_NUMBER CH4104K1B00
J 0
(3150 1450);
DISPLAY 0.510638 (3150 1450);
PAINT WHITE (3150 1450);
FORCEPROP 1 LAST MATERIAL X7R
J 0
(3150 1500);
DISPLAY 0.510638 (3150 1500);
PAINT SKYBLUE (3150 1500);
FORCEPROP 2 LAST CDS_LIB pure_quanta
J 0
(3100 1600);
DISPLAY INVISIBLE (3100 1600);
FORCEPROP 1 LAST PATH I278
J 0
(3150 1750);
DISPLAY 0.978723 (3150 1750);
PAINT WHITE (3150 1750);
DISPLAY INVISIBLE (3150 1750);
FORCEPROP 1 LAST LOCATION C255
J 0
(3150 1700);
DISPLAY 0.702128 (3150 1700);
PAINT YELLOW (3150 1700);
FORCEPROP 1 LASTPIN (3100 1700) $PN 1
J 0
(3110 1680);
DISPLAY 0.808511 (3110 1680);
PAINT WHITE (3110 1680);
FORCEPROP 1 LASTPIN (3100 1500) $PN 2
J 0
(3110 1480);
DISPLAY 0.808511 (3110 1480);
PAINT WHITE (3110 1480);
FORCEPROP 0 LAST $SEC 1
J 0
(3150 1750);
DISPLAY 0.680851 (3150 1750);
PAINT MONO (3150 1750);
DISPLAY INVISIBLE (3150 1750);
FORCEPROP 0 LAST CDS_SEC 1
J 0
(3150 1750);
DISPLAY 0.680851 (3150 1750);
DISPLAY INVISIBLE (3150 1750);
FORCEADD OFFPAGE..1
(375 1350);
FORCEPROP 2 LAST $XR0 44 
J 0
(154 1350);
DISPLAY 0.638298 (154 1350);
PAINT MONO (154 1350);
FORCEPROP 2 LAST CDS_LIB standard
J 0
(375 1350);
DISPLAY INVISIBLE (375 1350);
FORCEPROP 1 LAST OFFPAGE TRUE
J 0
(700 1225);
DISPLAY 0.872340 (700 1225);
PAINT GREEN (700 1225);
DISPLAY INVISIBLE (700 1225);
FORCEPROP 1 LAST COMMENT_BODY TRUE
J 0
(500 1250);
DISPLAY 0.872340 (500 1250);
PAINT PEACH (500 1250);
DISPLAY INVISIBLE (500 1250);
FORCEPROP 2 LAST PATH I279
J 0
(125 1400);
DISPLAY 1.021277 (125 1400);
DISPLAY INVISIBLE (125 1400);
FORCEADD OFFPAGE..1
(375 1400);
FORCEPROP 2 LAST $XR0 44 
J 0
(154 1400);
DISPLAY 0.638298 (154 1400);
PAINT MONO (154 1400);
FORCEPROP 2 LAST CDS_LIB standard
J 0
(375 1400);
DISPLAY INVISIBLE (375 1400);
FORCEPROP 1 LAST OFFPAGE TRUE
J 0
(700 1275);
DISPLAY 0.872340 (700 1275);
PAINT GREEN (700 1275);
DISPLAY INVISIBLE (700 1275);
FORCEPROP 1 LAST COMMENT_BODY TRUE
J 0
(500 1300);
DISPLAY 0.872340 (500 1300);
PAINT PEACH (500 1300);
DISPLAY INVISIBLE (500 1300);
FORCEPROP 2 LAST PATH I280
J 0
(125 1450);
DISPLAY 1.021277 (125 1450);
DISPLAY INVISIBLE (125 1450);
FORCEADD OFFPAGE..1
(375 1250);
FORCEPROP 2 LAST $XR0 44 
J 0
(154 1250);
DISPLAY 0.638298 (154 1250);
PAINT MONO (154 1250);
FORCEPROP 2 LAST CDS_LIB standard
J 0
(375 1250);
DISPLAY INVISIBLE (375 1250);
FORCEPROP 1 LAST OFFPAGE TRUE
J 0
(700 1125);
DISPLAY 0.872340 (700 1125);
PAINT GREEN (700 1125);
DISPLAY INVISIBLE (700 1125);
FORCEPROP 1 LAST COMMENT_BODY TRUE
J 0
(500 1150);
DISPLAY 0.872340 (500 1150);
PAINT PEACH (500 1150);
DISPLAY INVISIBLE (500 1150);
FORCEPROP 2 LAST PATH I281
J 0
(125 1300);
DISPLAY 1.021277 (125 1300);
DISPLAY INVISIBLE (125 1300);
FORCEADD OFFPAGE..1
(375 1200);
FORCEPROP 2 LAST $XR0 44 
J 0
(154 1200);
DISPLAY 0.638298 (154 1200);
PAINT MONO (154 1200);
FORCEPROP 2 LAST CDS_LIB standard
J 0
(375 1200);
DISPLAY INVISIBLE (375 1200);
FORCEPROP 1 LAST OFFPAGE TRUE
J 0
(700 1075);
DISPLAY 0.872340 (700 1075);
PAINT GREEN (700 1075);
DISPLAY INVISIBLE (700 1075);
FORCEPROP 1 LAST COMMENT_BODY TRUE
J 0
(500 1100);
DISPLAY 0.872340 (500 1100);
PAINT PEACH (500 1100);
DISPLAY INVISIBLE (500 1100);
FORCEPROP 2 LAST PATH I282
J 0
(125 1250);
DISPLAY 1.021277 (125 1250);
DISPLAY INVISIBLE (125 1250);
FORCEADD OFFPAGE..1
(400 -300);
FORCEPROP 2 LAST $XR0 44 
J 0
(179 -300);
DISPLAY 0.638298 (179 -300);
PAINT MONO (179 -300);
FORCEPROP 2 LAST CDS_LIB standard
J 0
(400 -300);
DISPLAY INVISIBLE (400 -300);
FORCEPROP 1 LAST OFFPAGE TRUE
J 0
(725 -425);
DISPLAY 0.872340 (725 -425);
PAINT GREEN (725 -425);
DISPLAY INVISIBLE (725 -425);
FORCEPROP 1 LAST COMMENT_BODY TRUE
J 0
(525 -400);
DISPLAY 0.872340 (525 -400);
PAINT PEACH (525 -400);
DISPLAY INVISIBLE (525 -400);
FORCEPROP 2 LAST PATH I283
J 0
(150 -250);
DISPLAY 1.021277 (150 -250);
DISPLAY INVISIBLE (150 -250);
FORCEADD OFFPAGE..1
(400 -350);
FORCEPROP 2 LAST $XR0 44 
J 0
(179 -350);
DISPLAY 0.638298 (179 -350);
PAINT MONO (179 -350);
FORCEPROP 2 LAST CDS_LIB standard
J 0
(400 -350);
DISPLAY INVISIBLE (400 -350);
FORCEPROP 1 LAST OFFPAGE TRUE
J 0
(725 -475);
DISPLAY 0.872340 (725 -475);
PAINT GREEN (725 -475);
DISPLAY INVISIBLE (725 -475);
FORCEPROP 1 LAST COMMENT_BODY TRUE
J 0
(525 -450);
DISPLAY 0.872340 (525 -450);
PAINT PEACH (525 -450);
DISPLAY INVISIBLE (525 -450);
FORCEPROP 2 LAST PATH I284
J 0
(150 -300);
DISPLAY 1.021277 (150 -300);
DISPLAY INVISIBLE (150 -300);
FORCEADD OFFPAGE..5
(400 -450);
FORCEPROP 2 LAST $XR0 44 
J 0
(146 -450);
DISPLAY 0.638298 (146 -450);
PAINT MONO (146 -450);
FORCEPROP 2 LAST CDS_LIB standard
J 0
(400 -450);
DISPLAY INVISIBLE (400 -450);
FORCEPROP 1 LAST OFFPAGE TRUE
J 0
(725 -575);
DISPLAY 0.872340 (725 -575);
PAINT GREEN (725 -575);
DISPLAY INVISIBLE (725 -575);
FORCEPROP 1 LAST COMMENT_BODY TRUE
J 0
(500 -525);
DISPLAY 0.872340 (500 -525);
PAINT PEACH (500 -525);
DISPLAY INVISIBLE (500 -525);
FORCEPROP 2 LAST PATH I285
J 0
(200 -400);
DISPLAY 1.021277 (200 -400);
DISPLAY INVISIBLE (200 -400);
FORCEADD OFFPAGE..5
(400 -500);
FORCEPROP 2 LAST $XR0 44 
J 0
(146 -500);
DISPLAY 0.638298 (146 -500);
PAINT MONO (146 -500);
FORCEPROP 2 LAST CDS_LIB standard
J 0
(400 -500);
DISPLAY INVISIBLE (400 -500);
FORCEPROP 1 LAST OFFPAGE TRUE
J 0
(725 -625);
DISPLAY 0.872340 (725 -625);
PAINT GREEN (725 -625);
DISPLAY INVISIBLE (725 -625);
FORCEPROP 1 LAST COMMENT_BODY TRUE
J 0
(500 -575);
DISPLAY 0.872340 (500 -575);
PAINT PEACH (500 -575);
DISPLAY INVISIBLE (500 -575);
FORCEPROP 2 LAST PATH I286
J 0
(200 -450);
DISPLAY 1.021277 (200 -450);
DISPLAY INVISIBLE (200 -450);
FORCEADD OFFPAGE..1
(375 1100);
FORCEPROP 2 LAST $XR0 44 
J 0
(154 1100);
DISPLAY 0.638298 (154 1100);
PAINT MONO (154 1100);
FORCEPROP 2 LAST CDS_LIB standard
J 0
(375 1100);
DISPLAY INVISIBLE (375 1100);
FORCEPROP 1 LAST OFFPAGE TRUE
J 0
(700 975);
DISPLAY 0.872340 (700 975);
PAINT GREEN (700 975);
DISPLAY INVISIBLE (700 975);
FORCEPROP 1 LAST COMMENT_BODY TRUE
J 0
(500 1000);
DISPLAY 0.872340 (500 1000);
PAINT PEACH (500 1000);
DISPLAY INVISIBLE (500 1000);
FORCEPROP 2 LAST PATH I287
J 0
(125 1150);
DISPLAY 1.021277 (125 1150);
DISPLAY INVISIBLE (125 1150);
FORCEADD OFFPAGE..1
(375 1050);
FORCEPROP 2 LAST $XR0 44 
J 0
(154 1050);
DISPLAY 0.638298 (154 1050);
PAINT MONO (154 1050);
FORCEPROP 2 LAST CDS_LIB standard
J 0
(375 1050);
DISPLAY INVISIBLE (375 1050);
FORCEPROP 1 LAST OFFPAGE TRUE
J 0
(700 925);
DISPLAY 0.872340 (700 925);
PAINT GREEN (700 925);
DISPLAY INVISIBLE (700 925);
FORCEPROP 1 LAST COMMENT_BODY TRUE
J 0
(500 950);
DISPLAY 0.872340 (500 950);
PAINT PEACH (500 950);
DISPLAY INVISIBLE (500 950);
FORCEPROP 2 LAST PATH I288
J 0
(125 1100);
DISPLAY 1.021277 (125 1100);
DISPLAY INVISIBLE (125 1100);
FORCEADD OFFPAGE..5
R 2
(4325 -500);
FORCEPROP 2 LAST $XR0 45 
J 0
(4514 -500);
DISPLAY 0.638298 (4514 -500);
PAINT MONO (4514 -500);
FORCEPROP 2 LAST CDS_LIB standard
J 0
(4325 -500);
DISPLAY INVISIBLE (4325 -500);
FORCEPROP 1 LAST OFFPAGE TRUE
J 2
(4000 -625);
DISPLAY 0.872340 (4000 -625);
PAINT GREEN (4000 -625);
DISPLAY INVISIBLE (4000 -625);
FORCEPROP 1 LAST COMMENT_BODY TRUE
J 2
(4225 -575);
DISPLAY 0.872340 (4225 -575);
PAINT PEACH (4225 -575);
DISPLAY INVISIBLE (4225 -575);
FORCEPROP 2 LAST PATH I289
J 0
(4625 -450);
DISPLAY 1.021277 (4625 -450);
DISPLAY INVISIBLE (4625 -450);
FORCEADD OFFPAGE..5
R 2
(4325 -600);
FORCEPROP 2 LAST $XR0 45 
J 0
(4514 -600);
DISPLAY 0.638298 (4514 -600);
PAINT MONO (4514 -600);
FORCEPROP 2 LAST CDS_LIB standard
J 0
(4325 -600);
DISPLAY INVISIBLE (4325 -600);
FORCEPROP 1 LAST OFFPAGE TRUE
J 2
(4000 -725);
DISPLAY 0.872340 (4000 -725);
PAINT GREEN (4000 -725);
DISPLAY INVISIBLE (4000 -725);
FORCEPROP 1 LAST COMMENT_BODY TRUE
J 2
(4225 -675);
DISPLAY 0.872340 (4225 -675);
PAINT PEACH (4225 -675);
DISPLAY INVISIBLE (4225 -675);
FORCEPROP 2 LAST PATH I290
J 0
(4625 -550);
DISPLAY 1.021277 (4625 -550);
DISPLAY INVISIBLE (4625 -550);
FORCEADD OFFPAGE..5
R 2
(4325 -700);
FORCEPROP 2 LAST $XR0 45 
J 0
(4514 -700);
DISPLAY 0.638298 (4514 -700);
PAINT MONO (4514 -700);
FORCEPROP 2 LAST CDS_LIB standard
J 0
(4325 -700);
DISPLAY INVISIBLE (4325 -700);
FORCEPROP 1 LAST OFFPAGE TRUE
J 2
(4000 -825);
DISPLAY 0.872340 (4000 -825);
PAINT GREEN (4000 -825);
DISPLAY INVISIBLE (4000 -825);
FORCEPROP 1 LAST COMMENT_BODY TRUE
J 2
(4225 -775);
DISPLAY 0.872340 (4225 -775);
PAINT PEACH (4225 -775);
DISPLAY INVISIBLE (4225 -775);
FORCEPROP 2 LAST PATH I291
J 0
(4625 -650);
DISPLAY 1.021277 (4625 -650);
DISPLAY INVISIBLE (4625 -650);
FORCEADD Q_CAP..1
(3125 -100);
FORCEPROP 1 LAST MATERIAL X7R
J 0
(3175 -200);
DISPLAY 0.510638 (3175 -200);
PAINT SKYBLUE (3175 -200);
FORCEPROP 1 LAST TOLERANCE 10%
J 0
(3175 -150);
DISPLAY 0.510638 (3175 -150);
PAINT SKYBLUE (3175 -150);
FORCEPROP 1 LAST VALUE 0.1UF
J 0
(3175 -50);
DISPLAY 0.510638 (3175 -50);
PAINT SKYBLUE (3175 -50);
FORCEPROP 1 LAST VOLTAGE 25V
J 0
(3175 -100);
DISPLAY 0.510638 (3175 -100);
PAINT SKYBLUE (3175 -100);
FORCEPROP 1 LAST PART_NUMBER CH4104K1B00
J 0
(3175 -250);
DISPLAY 0.510638 (3175 -250);
PAINT WHITE (3175 -250);
FORCEPROP 1 LAST PACK_TYPE 0402
J 0
(3175 -300);
DISPLAY 0.510638 (3175 -300);
PAINT SKYBLUE (3175 -300);
FORCEPROP 2 LAST CDS_LIB pure_quanta
J 0
(3125 -100);
DISPLAY INVISIBLE (3125 -100);
FORCEPROP 1 LAST PATH I292
J 0
(3175 50);
DISPLAY 0.978723 (3175 50);
PAINT WHITE (3175 50);
DISPLAY INVISIBLE (3175 50);
FORCEPROP 1 LAST LOCATION C146
J 0
(3175 0);
DISPLAY 0.702128 (3175 0);
PAINT YELLOW (3175 0);
FORCEPROP 1 LASTPIN (3125 0) $PN 1
J 0
(3135 -20);
DISPLAY 0.808511 (3135 -20);
PAINT WHITE (3135 -20);
FORCEPROP 1 LASTPIN (3125 -200) $PN 2
J 0
(3135 -220);
DISPLAY 0.808511 (3135 -220);
PAINT WHITE (3135 -220);
FORCEPROP 0 LAST $SEC 1
J 0
(3175 50);
DISPLAY 0.680851 (3175 50);
PAINT MONO (3175 50);
DISPLAY INVISIBLE (3175 50);
FORCEPROP 0 LAST CDS_SEC 1
J 0
(3175 50);
DISPLAY 0.680851 (3175 50);
DISPLAY INVISIBLE (3175 50);
FORCEADD UNIVERSAL_GND..1
R 2
(3125 -300);
FORCEPROP 3 LASTPIN (3125 -250) SIG_NAME GND\g
J 0
(3135 -240);
DISPLAY 0.659574 (3135 -240);
PAINT MONO (3135 -240);
DISPLAY INVISIBLE (3135 -240);
FORCEPROP 2 LAST CDS_LIB logical_power
J 0
(3125 -300);
DISPLAY INVISIBLE (3125 -300);
FORCEPROP 1 LAST HDL_POWER GND
J 1
(3100 -375);
DISPLAY 0.702128 (3100 -375);
PAINT GREEN (3100 -375);
DISPLAY INVISIBLE (3100 -375);
FORCEPROP 1 LAST PATH I293
J 2
(3050 -300);
DISPLAY 0.872340 (3050 -300);
PAINT AQUA (3050 -300);
DISPLAY INVISIBLE (3050 -300);
FORCEADD UNIVERSAL_GND..1
(3300 -1100);
FORCEPROP 3 LASTPIN (3300 -1050) SIG_NAME GND\g
J 0
(3310 -1040);
DISPLAY 0.659574 (3310 -1040);
PAINT MONO (3310 -1040);
DISPLAY INVISIBLE (3310 -1040);
FORCEPROP 2 LAST CDS_LIB logical_power
J 0
(3300 -1100);
DISPLAY INVISIBLE (3300 -1100);
FORCEPROP 1 LAST HDL_POWER GND
J 1
(3284 -1134);
DISPLAY 0.702128 (3284 -1134);
PAINT GREEN (3284 -1134);
DISPLAY INVISIBLE (3284 -1134);
FORCEPROP 1 LAST PATH I294
J 0
(3375 -1100);
DISPLAY 0.872340 (3375 -1100);
PAINT AQUA (3375 -1100);
DISPLAY INVISIBLE (3375 -1100);
FORCEADD P3V3_AUX..1
(2950 150);
FORCEPROP 3 LASTPIN (2950 100) SIG_NAME P3V3_AUX\g
J 0
(2960 110);
DISPLAY 0.659574 (2960 110);
PAINT MONO (2960 110);
DISPLAY INVISIBLE (2960 110);
FORCEPROP 1 LAST SIZE 1B
J 0
(2995 172);
DISPLAY 0.340426 (2995 172);
PAINT GREEN (2995 172);
DISPLAY INVISIBLE (2995 172);
FORCEPROP 2 LAST CDS_LIB logical_power
J 0
(2950 150);
DISPLAY INVISIBLE (2950 150);
FORCEPROP 1 LAST BODY_TYPE PLUMBING
J 0
(2905 107);
DISPLAY 0.340426 (2905 107);
PAINT GREEN (2905 107);
DISPLAY INVISIBLE (2905 107);
FORCEPROP 1 LAST HDL_POWER P3V3_AUX
J 0
(2650 25);
DISPLAY 0.702128 (2650 25);
DISPLAY INVISIBLE (2650 25);
FORCEPROP 1 LAST PATH I295
J 0
(2995 152);
DISPLAY 0.340426 (2995 152);
PAINT GREEN (2995 152);
DISPLAY INVISIBLE (2995 152);
FORCEADD IDTQS3VH257PAG..1
R 2
(2350 -650);
FORCEPROP 1 LAST VALUE IDTQS3VH257PAG
J 2
(2602 20);
DISPLAY 0.510638 (2602 20);
PAINT SKYBLUE (2602 20);
FORCEPROP 1 LAST PART_NUMBER AL000257K00
J 2
(2602 -140);
DISPLAY 0.510638 (2602 -140);
PAINT WHITE (2602 -140);
FORCEPROP 1 LAST MATERIAL IC
J 2
(2602 -220);
DISPLAY 0.510638 (2602 -220);
PAINT SKYBLUE (2602 -220);
FORCEPROP 1 LAST CDS_LMAN_SYM_OUTLINE -250,400,250,-500
J 2
(2500 -700);
DISPLAY 0.468085 (2500 -700);
PAINT GREEN (2500 -700);
DISPLAY INVISIBLE (2500 -700);
FORCEPROP 2 LAST CDS_LIB pure_quanta
J 2
(2350 -650);
DISPLAY INVISIBLE (2350 -650);
FORCEPROP 0 LAST MANUF_PN IDTQS3VH257PAG
J 2
(2600 125);
DISPLAY 1.021277 (2600 125);
DISPLAY INVISIBLE (2600 125);
FORCEPROP 2 LAST SEC_TYPE SMLF
J 0
(2625 100);
DISPLAY 1.021277 (2625 100);
DISPLAY INVISIBLE (2625 100);
FORCEPROP 1 LAST PACK_TYPE SMLF
J 2
(2500 -1300);
DISPLAY 0.510638 (2500 -1300);
PAINT SKYBLUE (2500 -1300);
DISPLAY INVISIBLE (2500 -1300);
FORCEPROP 0 LAST PATH I296
J 0
(2625 50);
DISPLAY 1.021277 (2625 50);
DISPLAY INVISIBLE (2625 50);
FORCEPROP 1 LAST LOCATION U21
J 2
(2602 -60);
DISPLAY 0.702128 (2602 -60);
PAINT AQUA (2602 -60);
FORCEPROP 1 LASTPIN (1950 -1050) $PN 15
J 2
(2060 -1047);
DISPLAY 0.808511 (2060 -1047);
PAINT WHITE (2060 -1047);
FORCEPROP 1 LASTPIN (2750 -950) $PN 8
J 0
(2640 -947);
DISPLAY 0.808511 (2640 -947);
PAINT WHITE (2640 -947);
FORCEPROP 1 LASTPIN (1950 -350) $PN 2
J 2
(2060 -347);
DISPLAY 0.808511 (2060 -347);
PAINT WHITE (2060 -347);
FORCEPROP 1 LASTPIN (1950 -500) $PN 5
J 2
(2060 -497);
DISPLAY 0.808511 (2060 -497);
PAINT WHITE (2060 -497);
FORCEPROP 1 LASTPIN (1950 -650) $PN 11
J 2
(2060 -647);
DISPLAY 0.808511 (2060 -647);
PAINT WHITE (2060 -647);
FORCEPROP 1 LASTPIN (1950 -800) $PN 14
J 2
(2060 -797);
DISPLAY 0.808511 (2060 -797);
PAINT WHITE (2060 -797);
FORCEPROP 1 LASTPIN (1950 -300) $PN 3
J 2
(2060 -297);
DISPLAY 0.808511 (2060 -297);
PAINT WHITE (2060 -297);
FORCEPROP 1 LASTPIN (1950 -450) $PN 6
J 2
(2060 -447);
DISPLAY 0.808511 (2060 -447);
PAINT WHITE (2060 -447);
FORCEPROP 1 LASTPIN (1950 -600) $PN 10
J 2
(2060 -597);
DISPLAY 0.808511 (2060 -597);
PAINT WHITE (2060 -597);
FORCEPROP 1 LASTPIN (1950 -750) $PN 13
J 2
(2060 -747);
DISPLAY 0.808511 (2060 -747);
PAINT WHITE (2060 -747);
FORCEPROP 1 LASTPIN (1950 -950) $PN 1
J 2
(2060 -947);
DISPLAY 0.808511 (2060 -947);
PAINT WHITE (2060 -947);
FORCEPROP 1 LASTPIN (2750 -350) $PN 16
J 0
(2640 -347);
DISPLAY 0.808511 (2640 -347);
PAINT WHITE (2640 -347);
FORCEPROP 1 LASTPIN (2750 -500) $PN 4
J 0
(2640 -497);
DISPLAY 0.808511 (2640 -497);
PAINT WHITE (2640 -497);
FORCEPROP 1 LASTPIN (2750 -600) $PN 7
J 0
(2640 -597);
DISPLAY 0.808511 (2640 -597);
PAINT WHITE (2640 -597);
FORCEPROP 1 LASTPIN (2750 -700) $PN 9
J 0
(2640 -697);
DISPLAY 0.808511 (2640 -697);
PAINT WHITE (2640 -697);
FORCEPROP 1 LASTPIN (2750 -800) $PN 12
J 0
(2640 -797);
DISPLAY 0.808511 (2640 -797);
PAINT WHITE (2640 -797);
FORCEPROP 0 LAST SEC 1
J 0
(2625 50);
DISPLAY INVISIBLE (2625 50);
FORCEADD OFFPAGE..1
(-275 -950);
FORCEPROP 2 LAST $XR0 44 
J 0
(-496 -950);
DISPLAY 0.638298 (-496 -950);
PAINT MONO (-496 -950);
FORCEPROP 2 LAST CDS_LIB standard
J 0
(-275 -950);
DISPLAY INVISIBLE (-275 -950);
FORCEPROP 1 LAST OFFPAGE TRUE
J 0
(50 -1075);
DISPLAY 0.872340 (50 -1075);
PAINT GREEN (50 -1075);
DISPLAY INVISIBLE (50 -1075);
FORCEPROP 1 LAST COMMENT_BODY TRUE
J 0
(-150 -1050);
DISPLAY 0.872340 (-150 -1050);
PAINT PEACH (-150 -1050);
DISPLAY INVISIBLE (-150 -1050);
FORCEPROP 2 LAST PATH I305
J 0
(-475 -900);
DISPLAY 1.021277 (-475 -900);
DISPLAY INVISIBLE (-475 -900);
FORCEADD OFFPAGE..1
(-275 -1050);
FORCEPROP 2 LAST $XR0 13 
J 0
(-496 -1050);
DISPLAY 0.638298 (-496 -1050);
PAINT MONO (-496 -1050);
FORCEPROP 2 LAST $XR1 44 
J 0
(-586 -1050);
DISPLAY 0.638298 (-586 -1050);
PAINT MONO (-586 -1050);
FORCEPROP 2 LAST CDS_LIB standard
J 0
(-275 -1050);
DISPLAY INVISIBLE (-275 -1050);
FORCEPROP 1 LAST OFFPAGE TRUE
J 0
(50 -1175);
DISPLAY 0.872340 (50 -1175);
PAINT GREEN (50 -1175);
DISPLAY INVISIBLE (50 -1175);
FORCEPROP 1 LAST COMMENT_BODY TRUE
J 0
(-150 -1150);
DISPLAY 0.872340 (-150 -1150);
PAINT PEACH (-150 -1150);
DISPLAY INVISIBLE (-150 -1150);
FORCEPROP 2 LAST PATH I306
J 0
(-475 -1000);
DISPLAY 1.021277 (-475 -1000);
DISPLAY INVISIBLE (-475 -1000);
FORCEADD OFFPAGE..1
(400 -600);
FORCEPROP 2 LAST $XR0 44 
J 0
(179 -600);
DISPLAY 0.638298 (179 -600);
PAINT MONO (179 -600);
FORCEPROP 2 LAST CDS_LIB standard
J 0
(400 -600);
DISPLAY INVISIBLE (400 -600);
FORCEPROP 1 LAST OFFPAGE TRUE
J 0
(725 -725);
DISPLAY 0.872340 (725 -725);
PAINT GREEN (725 -725);
DISPLAY INVISIBLE (725 -725);
FORCEPROP 1 LAST COMMENT_BODY TRUE
J 0
(525 -700);
DISPLAY 0.872340 (525 -700);
PAINT PEACH (525 -700);
DISPLAY INVISIBLE (525 -700);
FORCEPROP 2 LAST PATH I309
J 0
(150 -550);
DISPLAY 1.021277 (150 -550);
DISPLAY INVISIBLE (150 -550);
FORCEADD OFFPAGE..1
(400 -650);
FORCEPROP 2 LAST $XR0 44 
J 0
(179 -650);
DISPLAY 0.638298 (179 -650);
PAINT MONO (179 -650);
FORCEPROP 2 LAST CDS_LIB standard
J 0
(400 -650);
DISPLAY INVISIBLE (400 -650);
FORCEPROP 1 LAST OFFPAGE TRUE
J 0
(725 -775);
DISPLAY 0.872340 (725 -775);
PAINT GREEN (725 -775);
DISPLAY INVISIBLE (725 -775);
FORCEPROP 1 LAST COMMENT_BODY TRUE
J 0
(525 -750);
DISPLAY 0.872340 (525 -750);
PAINT PEACH (525 -750);
DISPLAY INVISIBLE (525 -750);
FORCEPROP 2 LAST PATH I310
J 0
(150 -600);
DISPLAY 1.021277 (150 -600);
DISPLAY INVISIBLE (150 -600);
FORCEADD Q_RES..2
R 2
(1775 -1450);
FORCEPROP 1 LAST PART_NUMBER CS31002FB08
J 2
(1735 -1575);
DISPLAY 0.510638 (1735 -1575);
PAINT WHITE (1735 -1575);
FORCEPROP 1 LAST TOLERANCE 1%
J 2
(1730 -1425);
DISPLAY 0.510638 (1730 -1425);
PAINT SKYBLUE (1730 -1425);
FORCEPROP 1 LAST WATTAGE 1/16W
J 2
(1735 -1475);
DISPLAY 0.510638 (1735 -1475);
PAINT SKYBLUE (1735 -1475);
FORCEPROP 1 LAST MATERIAL CHIP
J 2
(1735 -1525);
DISPLAY 0.510638 (1735 -1525);
PAINT SKYBLUE (1735 -1525);
FORCEPROP 1 LAST VALUE 10K
J 2
(1730 -1375);
DISPLAY 0.510638 (1730 -1375);
PAINT SKYBLUE (1730 -1375);
FORCEPROP 1 LAST PACK_TYPE 0402LF
J 2
(1735 -1625);
DISPLAY 0.510638 (1735 -1625);
PAINT SKYBLUE (1735 -1625);
FORCEPROP 2 LAST CDS_LIB pure_quanta
J 0
(1775 -1450);
DISPLAY INVISIBLE (1775 -1450);
FORCEPROP 1 LAST PATH I311
J 2
(1725 -1275);
DISPLAY 0.978723 (1725 -1275);
PAINT WHITE (1725 -1275);
DISPLAY INVISIBLE (1725 -1275);
FORCEPROP 1 LAST LOCATION R866
J 2
(1730 -1325);
DISPLAY 0.702128 (1730 -1325);
PAINT YELLOW (1730 -1325);
FORCEPROP 0 LAST $SEC 1
J 0
(1750 -1275);
DISPLAY 0.680851 (1750 -1275);
PAINT MONO (1750 -1275);
DISPLAY INVISIBLE (1750 -1275);
FORCEPROP 0 LAST CDS_SEC 1
J 2
(1725 -1275);
DISPLAY 1.021277 (1725 -1275);
DISPLAY INVISIBLE (1725 -1275);
FORCEPROP 1 LASTPIN (1775 -1350) $PN 1
J 2
(1770 -1388);
DISPLAY 0.808511 (1770 -1388);
PAINT WHITE (1770 -1388);
DISPLAY INVISIBLE (1770 -1388);
FORCEPROP 1 LASTPIN (1775 -1550) $PN 2
J 2
(1770 -1540);
DISPLAY 0.808511 (1770 -1540);
PAINT WHITE (1770 -1540);
DISPLAY INVISIBLE (1770 -1540);
FORCEADD UNIVERSAL_GND..1
(1775 -1650);
FORCEPROP 3 LASTPIN (1775 -1600) SIG_NAME GND\g
J 0
(1785 -1590);
DISPLAY 0.659574 (1785 -1590);
PAINT MONO (1785 -1590);
DISPLAY INVISIBLE (1785 -1590);
FORCEPROP 2 LAST CDS_LIB logical_power
J 0
(1775 -1650);
DISPLAY INVISIBLE (1775 -1650);
FORCEPROP 1 LAST HDL_POWER GND
J 1
(1800 -1725);
DISPLAY 0.702128 (1800 -1725);
PAINT GREEN (1800 -1725);
DISPLAY INVISIBLE (1800 -1725);
FORCEPROP 1 LAST PATH I312
J 0
(1850 -1650);
DISPLAY 0.872340 (1850 -1650);
PAINT AQUA (1850 -1650);
DISPLAY INVISIBLE (1850 -1650);
FORCEADD Q_RES..2
(1250 -1375);
FORCEPROP 1 LAST TOLERANCE 1%
J 0
(1295 -1350);
DISPLAY 0.510638 (1295 -1350);
PAINT SKYBLUE (1295 -1350);
FORCEPROP 1 LAST VALUE 2K
J 0
(1295 -1300);
DISPLAY 0.510638 (1295 -1300);
PAINT SKYBLUE (1295 -1300);
FORCEPROP 1 LAST PACK_TYPE 0402LF
J 0
(1300 -1500);
DISPLAY 0.510638 (1300 -1500);
PAINT SKYBLUE (1300 -1500);
FORCEPROP 1 LAST MATERIAL CHIP
J 0
(1290 -1450);
DISPLAY 0.510638 (1290 -1450);
PAINT SKYBLUE (1290 -1450);
FORCEPROP 1 LAST WATTAGE 1/16W
J 0
(1290 -1400);
DISPLAY 0.510638 (1290 -1400);
PAINT SKYBLUE (1290 -1400);
FORCEPROP 2 LAST CDS_LIB pure_quanta
J 0
(1250 -1375);
DISPLAY INVISIBLE (1250 -1375);
FORCEPROP 1 LAST PATH I313
J 0
(1300 -1200);
DISPLAY 0.978723 (1300 -1200);
PAINT WHITE (1300 -1200);
DISPLAY INVISIBLE (1300 -1200);
FORCEPROP 1 LAST PART_NUMBER CS22002FB07
J 0
(1290 -1500);
DISPLAY 0.510638 (1290 -1500);
PAINT WHITE (1290 -1500);
DISPLAY INVISIBLE (1290 -1500);
FORCEPROP 1 LAST LOCATION R467
J 0
(1295 -1250);
DISPLAY 0.702128 (1295 -1250);
PAINT YELLOW (1295 -1250);
FORCEPROP 0 LAST $SEC 1
J 0
(1300 -1200);
DISPLAY 0.680851 (1300 -1200);
PAINT MONO (1300 -1200);
DISPLAY INVISIBLE (1300 -1200);
FORCEPROP 0 LAST CDS_SEC 1
J 0
(1300 -1200);
DISPLAY 1.021277 (1300 -1200);
DISPLAY INVISIBLE (1300 -1200);
FORCEPROP 1 LASTPIN (1250 -1275) $PN 1
J 0
(1255 -1313);
DISPLAY 0.808511 (1255 -1313);
PAINT WHITE (1255 -1313);
DISPLAY INVISIBLE (1255 -1313);
FORCEPROP 1 LASTPIN (1250 -1475) $PN 2
J 0
(1255 -1465);
DISPLAY 0.808511 (1255 -1465);
PAINT WHITE (1255 -1465);
DISPLAY INVISIBLE (1255 -1465);
FORCEADD UNIVERSAL_GND..1
(1250 -1575);
FORCEPROP 3 LASTPIN (1250 -1525) SIG_NAME GND\g
J 0
(1260 -1515);
DISPLAY 0.659574 (1260 -1515);
PAINT MONO (1260 -1515);
DISPLAY INVISIBLE (1260 -1515);
FORCEPROP 2 LAST CDS_LIB logical_power
J 0
(1250 -1575);
DISPLAY INVISIBLE (1250 -1575);
FORCEPROP 1 LAST HDL_POWER GND
J 1
(1275 -1650);
DISPLAY 0.702128 (1275 -1650);
PAINT GREEN (1275 -1650);
DISPLAY INVISIBLE (1275 -1650);
FORCEPROP 1 LAST PATH I314
J 0
(1325 -1575);
DISPLAY 0.872340 (1325 -1575);
PAINT AQUA (1325 -1575);
DISPLAY INVISIBLE (1325 -1575);
FORCEADD Q_RES..2
R 2
(475 -1400);
FORCEPROP 1 LAST PART_NUMBER CS24702FB06
J 2
(435 -1525);
DISPLAY 0.510638 (435 -1525);
PAINT WHITE (435 -1525);
FORCEPROP 1 LAST MATERIAL EMPTY
J 2
(435 -1475);
DISPLAY 0.510638 (435 -1475);
PAINT RED (435 -1475);
FORCEPROP 1 LAST WATTAGE 1/16W
J 2
(435 -1425);
DISPLAY 0.510638 (435 -1425);
PAINT SKYBLUE (435 -1425);
FORCEPROP 1 LAST TOLERANCE 1%
J 2
(430 -1375);
DISPLAY 0.510638 (430 -1375);
PAINT SKYBLUE (430 -1375);
FORCEPROP 1 LAST VALUE 4.7K
J 2
(430 -1325);
DISPLAY 0.510638 (430 -1325);
PAINT SKYBLUE (430 -1325);
FORCEPROP 1 LAST PACK_TYPE 0402LF
J 2
(435 -1575);
DISPLAY 0.510638 (435 -1575);
PAINT SKYBLUE (435 -1575);
FORCEPROP 2 LAST CDS_LIB pure_quanta
J 2
(475 -1400);
DISPLAY INVISIBLE (475 -1400);
FORCEPROP 1 LAST PATH I315
J 2
(425 -1225);
DISPLAY 0.978723 (425 -1225);
PAINT WHITE (425 -1225);
DISPLAY INVISIBLE (425 -1225);
FORCEPROP 1 LAST LOCATION R870
J 2
(430 -1275);
DISPLAY 0.702128 (430 -1275);
PAINT YELLOW (430 -1275);
FORCEPROP 0 LAST $SEC 1
J 0
(450 -1225);
DISPLAY 0.680851 (450 -1225);
PAINT MONO (450 -1225);
DISPLAY INVISIBLE (450 -1225);
FORCEPROP 0 LAST CDS_SEC 1
J 0
(450 -1225);
DISPLAY 1.021277 (450 -1225);
DISPLAY INVISIBLE (450 -1225);
FORCEPROP 1 LASTPIN (475 -1300) $PN 1
J 2
(470 -1338);
DISPLAY 0.808511 (470 -1338);
PAINT WHITE (470 -1338);
DISPLAY INVISIBLE (470 -1338);
FORCEPROP 1 LASTPIN (475 -1500) $PN 2
J 2
(470 -1490);
DISPLAY 0.808511 (470 -1490);
PAINT WHITE (470 -1490);
DISPLAY INVISIBLE (470 -1490);
FORCEADD P3V3_AUX..1
(475 -1200);
FORCEPROP 3 LASTPIN (475 -1250) SIG_NAME P3V3_AUX\g
J 0
(485 -1240);
DISPLAY 0.659574 (485 -1240);
PAINT MONO (485 -1240);
DISPLAY INVISIBLE (485 -1240);
FORCEPROP 2 LAST CDS_LIB logical_power
J 0
(475 -1200);
DISPLAY INVISIBLE (475 -1200);
FORCEPROP 1 LAST SIZE 1B
J 0
(520 -1178);
DISPLAY 0.340426 (520 -1178);
PAINT GREEN (520 -1178);
DISPLAY INVISIBLE (520 -1178);
FORCEPROP 1 LAST BODY_TYPE PLUMBING
J 0
(430 -1243);
DISPLAY 0.340426 (430 -1243);
PAINT GREEN (430 -1243);
DISPLAY INVISIBLE (430 -1243);
FORCEPROP 1 LAST HDL_POWER P3V3_AUX
J 0
(175 -1325);
DISPLAY 0.702128 (175 -1325);
DISPLAY INVISIBLE (175 -1325);
FORCEPROP 1 LAST PATH I316
J 0
(520 -1198);
DISPLAY 0.340426 (520 -1198);
PAINT GREEN (520 -1198);
DISPLAY INVISIBLE (520 -1198);
FORCEADD OFFPAGE..2
(-1200 2675);
FORCEPROP 2 LAST $XR0 44 
J 0
(-1011 2675);
DISPLAY 0.638298 (-1011 2675);
PAINT MONO (-1011 2675);
FORCEPROP 2 LAST CDS_LIB standard
J 0
(-1200 2675);
DISPLAY INVISIBLE (-1200 2675);
FORCEPROP 1 LAST OFFPAGE TRUE
J 0
(-875 2550);
DISPLAY 0.872340 (-875 2550);
PAINT GREEN (-875 2550);
DISPLAY INVISIBLE (-875 2550);
FORCEPROP 1 LAST COMMENT_BODY TRUE
J 0
(-1245 2580);
DISPLAY 0.872340 (-1245 2580);
PAINT PEACH (-1245 2580);
DISPLAY INVISIBLE (-1245 2580);
FORCEPROP 2 LAST PATH I317
J 0
(-1000 2725);
DISPLAY 0.680851 (-1000 2725);
DISPLAY INVISIBLE (-1000 2725);
FORCEADD OFFPAGE..2
(-1200 2625);
FORCEPROP 2 LAST $XR0 44 
J 0
(-1011 2625);
DISPLAY 0.638298 (-1011 2625);
PAINT MONO (-1011 2625);
FORCEPROP 2 LAST CDS_LIB standard
J 0
(-1200 2625);
DISPLAY INVISIBLE (-1200 2625);
FORCEPROP 1 LAST OFFPAGE TRUE
J 0
(-875 2500);
DISPLAY 0.872340 (-875 2500);
PAINT GREEN (-875 2500);
DISPLAY INVISIBLE (-875 2500);
FORCEPROP 1 LAST COMMENT_BODY TRUE
J 0
(-1245 2530);
DISPLAY 0.872340 (-1245 2530);
PAINT PEACH (-1245 2530);
DISPLAY INVISIBLE (-1245 2530);
FORCEPROP 2 LAST PATH I318
J 0
(-1000 2675);
DISPLAY 0.680851 (-1000 2675);
DISPLAY INVISIBLE (-1000 2675);
FORCEADD OFFPAGE..2
(-1200 2525);
FORCEPROP 2 LAST $XR0 44 
J 0
(-1011 2525);
DISPLAY 0.638298 (-1011 2525);
PAINT MONO (-1011 2525);
FORCEPROP 2 LAST CDS_LIB standard
J 0
(-1200 2525);
DISPLAY INVISIBLE (-1200 2525);
FORCEPROP 1 LAST OFFPAGE TRUE
J 0
(-875 2400);
DISPLAY 0.872340 (-875 2400);
PAINT GREEN (-875 2400);
DISPLAY INVISIBLE (-875 2400);
FORCEPROP 1 LAST COMMENT_BODY TRUE
J 0
(-1245 2430);
DISPLAY 0.872340 (-1245 2430);
PAINT PEACH (-1245 2430);
DISPLAY INVISIBLE (-1245 2430);
FORCEPROP 2 LAST PATH I319
J 0
(-1000 2575);
DISPLAY 0.680851 (-1000 2575);
DISPLAY INVISIBLE (-1000 2575);
FORCEADD OFFPAGE..2
(-1200 2475);
FORCEPROP 2 LAST $XR0 44 
J 0
(-1011 2475);
DISPLAY 0.638298 (-1011 2475);
PAINT MONO (-1011 2475);
FORCEPROP 2 LAST CDS_LIB standard
J 0
(-1200 2475);
DISPLAY INVISIBLE (-1200 2475);
FORCEPROP 1 LAST OFFPAGE TRUE
J 0
(-875 2350);
DISPLAY 0.872340 (-875 2350);
PAINT GREEN (-875 2350);
DISPLAY INVISIBLE (-875 2350);
FORCEPROP 1 LAST COMMENT_BODY TRUE
J 0
(-1245 2380);
DISPLAY 0.872340 (-1245 2380);
PAINT PEACH (-1245 2380);
DISPLAY INVISIBLE (-1245 2380);
FORCEPROP 2 LAST PATH I320
J 0
(-1000 2525);
DISPLAY 0.680851 (-1000 2525);
DISPLAY INVISIBLE (-1000 2525);
FORCEADD OFFPAGE..4
(-1200 2575);
FORCEPROP 2 LAST $XR0 44 
J 0
(-1014 2575);
DISPLAY 0.638298 (-1014 2575);
PAINT MONO (-1014 2575);
FORCEPROP 2 LAST CDS_LIB standard
J 0
(-1200 2575);
DISPLAY INVISIBLE (-1200 2575);
FORCEPROP 1 LAST OFFPAGE TRUE
J 0
(-875 2450);
DISPLAY 0.872340 (-875 2450);
PAINT GREEN (-875 2450);
DISPLAY INVISIBLE (-875 2450);
FORCEPROP 1 LAST COMMENT_BODY TRUE
J 0
(-1225 2475);
DISPLAY 0.872340 (-1225 2475);
PAINT PEACH (-1225 2475);
DISPLAY INVISIBLE (-1225 2475);
FORCEPROP 2 LAST PATH I321
J 0
(-1000 2625);
DISPLAY 0.680851 (-1000 2625);
DISPLAY INVISIBLE (-1000 2625);
FORCEADD OFFPAGE..5
R 2
(-1200 2300);
FORCEPROP 2 LAST $XR0 44 
J 0
(-1011 2300);
DISPLAY 0.638298 (-1011 2300);
PAINT MONO (-1011 2300);
FORCEPROP 2 LAST CDS_LIB standard
J 0
(-1200 2300);
DISPLAY INVISIBLE (-1200 2300);
FORCEPROP 1 LAST OFFPAGE TRUE
J 2
(-1525 2175);
DISPLAY 0.872340 (-1525 2175);
PAINT GREEN (-1525 2175);
DISPLAY INVISIBLE (-1525 2175);
FORCEPROP 1 LAST COMMENT_BODY TRUE
J 2
(-1300 2225);
DISPLAY 0.872340 (-1300 2225);
PAINT PEACH (-1300 2225);
DISPLAY INVISIBLE (-1300 2225);
FORCEPROP 2 LAST PATH I323
J 0
(-1000 2350);
DISPLAY 0.680851 (-1000 2350);
DISPLAY INVISIBLE (-1000 2350);
FORCEADD OFFPAGE..2
(-1175 1700);
FORCEPROP 2 LAST $XR0 44 
J 0
(-986 1700);
DISPLAY 0.638298 (-986 1700);
PAINT MONO (-986 1700);
FORCEPROP 2 LAST CDS_LIB standard
J 0
(-1175 1700);
DISPLAY INVISIBLE (-1175 1700);
FORCEPROP 1 LAST OFFPAGE TRUE
J 0
(-850 1575);
DISPLAY 0.872340 (-850 1575);
PAINT GREEN (-850 1575);
DISPLAY INVISIBLE (-850 1575);
FORCEPROP 1 LAST COMMENT_BODY TRUE
J 0
(-1220 1605);
DISPLAY 0.872340 (-1220 1605);
PAINT PEACH (-1220 1605);
DISPLAY INVISIBLE (-1220 1605);
FORCEPROP 2 LAST PATH I324
J 0
(-975 1750);
DISPLAY 0.680851 (-975 1750);
DISPLAY INVISIBLE (-975 1750);
FORCEADD OFFPAGE..2
(-1175 1550);
FORCEPROP 2 LAST $XR0 44 
J 0
(-986 1550);
DISPLAY 0.638298 (-986 1550);
PAINT MONO (-986 1550);
FORCEPROP 2 LAST CDS_LIB standard
J 0
(-1175 1550);
DISPLAY INVISIBLE (-1175 1550);
FORCEPROP 1 LAST OFFPAGE TRUE
J 0
(-850 1425);
DISPLAY 0.872340 (-850 1425);
PAINT GREEN (-850 1425);
DISPLAY INVISIBLE (-850 1425);
FORCEPROP 1 LAST COMMENT_BODY TRUE
J 0
(-1220 1455);
DISPLAY 0.872340 (-1220 1455);
PAINT PEACH (-1220 1455);
DISPLAY INVISIBLE (-1220 1455);
FORCEPROP 2 LAST PATH I325
J 0
(-975 1600);
DISPLAY 0.680851 (-975 1600);
DISPLAY INVISIBLE (-975 1600);
FORCEADD OFFPAGE..4
(-1175 1600);
FORCEPROP 2 LAST $XR0 44 
J 0
(-989 1600);
DISPLAY 0.638298 (-989 1600);
PAINT MONO (-989 1600);
FORCEPROP 2 LAST CDS_LIB standard
J 0
(-1175 1600);
DISPLAY INVISIBLE (-1175 1600);
FORCEPROP 1 LAST OFFPAGE TRUE
J 0
(-850 1475);
DISPLAY 0.872340 (-850 1475);
PAINT GREEN (-850 1475);
DISPLAY INVISIBLE (-850 1475);
FORCEPROP 1 LAST COMMENT_BODY TRUE
J 0
(-1200 1500);
DISPLAY 0.872340 (-1200 1500);
PAINT PEACH (-1200 1500);
DISPLAY INVISIBLE (-1200 1500);
FORCEPROP 2 LAST PATH I326
J 0
(-975 1650);
DISPLAY 0.680851 (-975 1650);
DISPLAY INVISIBLE (-975 1650);
FORCEADD OFFPAGE..2
(-1175 1500);
FORCEPROP 2 LAST $XR0 44 
J 0
(-986 1500);
DISPLAY 0.638298 (-986 1500);
PAINT MONO (-986 1500);
FORCEPROP 2 LAST CDS_LIB standard
J 0
(-1175 1500);
DISPLAY INVISIBLE (-1175 1500);
FORCEPROP 1 LAST OFFPAGE TRUE
J 0
(-850 1375);
DISPLAY 0.872340 (-850 1375);
PAINT GREEN (-850 1375);
DISPLAY INVISIBLE (-850 1375);
FORCEPROP 1 LAST COMMENT_BODY TRUE
J 0
(-1220 1405);
DISPLAY 0.872340 (-1220 1405);
PAINT PEACH (-1220 1405);
DISPLAY INVISIBLE (-1220 1405);
FORCEPROP 2 LAST PATH I327
J 0
(-975 1550);
DISPLAY 0.680851 (-975 1550);
DISPLAY INVISIBLE (-975 1550);
FORCEADD OFFPAGE..2
(-1175 1650);
FORCEPROP 2 LAST $XR0 44 
J 0
(-986 1650);
DISPLAY 0.638298 (-986 1650);
PAINT MONO (-986 1650);
FORCEPROP 2 LAST CDS_LIB standard
J 0
(-1175 1650);
DISPLAY INVISIBLE (-1175 1650);
FORCEPROP 1 LAST OFFPAGE TRUE
J 0
(-850 1525);
DISPLAY 0.872340 (-850 1525);
PAINT GREEN (-850 1525);
DISPLAY INVISIBLE (-850 1525);
FORCEPROP 1 LAST COMMENT_BODY TRUE
J 0
(-1220 1555);
DISPLAY 0.872340 (-1220 1555);
PAINT PEACH (-1220 1555);
DISPLAY INVISIBLE (-1220 1555);
FORCEPROP 2 LAST PATH I328
J 0
(-975 1700);
DISPLAY 0.680851 (-975 1700);
DISPLAY INVISIBLE (-975 1700);
FORCEADD OFFPAGE..2
(-1175 1450);
FORCEPROP 2 LAST $XR0 44 
J 0
(-986 1450);
DISPLAY 0.638298 (-986 1450);
PAINT MONO (-986 1450);
FORCEPROP 2 LAST CDS_LIB standard
J 0
(-1175 1450);
DISPLAY INVISIBLE (-1175 1450);
FORCEPROP 1 LAST OFFPAGE TRUE
J 0
(-850 1325);
DISPLAY 0.872340 (-850 1325);
PAINT GREEN (-850 1325);
DISPLAY INVISIBLE (-850 1325);
FORCEPROP 1 LAST COMMENT_BODY TRUE
J 0
(-1220 1355);
DISPLAY 0.872340 (-1220 1355);
PAINT PEACH (-1220 1355);
DISPLAY INVISIBLE (-1220 1355);
FORCEPROP 2 LAST PATH I329
J 0
(-975 1500);
DISPLAY 0.680851 (-975 1500);
DISPLAY INVISIBLE (-975 1500);
FORCEADD Q_RES..1
(-2625 2625);
FORCEPROP 1 LAST MATERIAL CHIP
J 2
(-2325 2625);
DISPLAY 0.510638 (-2325 2625);
PAINT SKYBLUE (-2325 2625);
FORCEPROP 1 LAST VALUE 33.2
J 2
(-2450 2625);
DISPLAY 0.510638 (-2450 2625);
PAINT SKYBLUE (-2450 2625);
FORCEPROP 2 LAST CDS_LIB pure_quanta
J 0
(-2625 2625);
DISPLAY INVISIBLE (-2625 2625);
FORCEPROP 1 LAST PATH I330
J 0
(-2675 2775);
DISPLAY 0.978723 (-2675 2775);
PAINT WHITE (-2675 2775);
DISPLAY INVISIBLE (-2675 2775);
FORCEPROP 1 LAST WATTAGE 1/16W
J 2
(-2275 2725);
DISPLAY 0.510638 (-2275 2725);
PAINT SKYBLUE (-2275 2725);
DISPLAY INVISIBLE (-2275 2725);
FORCEPROP 1 LAST PACK_TYPE 0402LF
J 0
(-2650 2675);
DISPLAY 0.510638 (-2650 2675);
PAINT SKYBLUE (-2650 2675);
DISPLAY INVISIBLE (-2650 2675);
FORCEPROP 1 LAST PART_NUMBER CS03322FB03
J 0
(-2725 2700);
DISPLAY 0.510638 (-2725 2700);
PAINT WHITE (-2725 2700);
DISPLAY INVISIBLE (-2725 2700);
FORCEPROP 1 LAST TOLERANCE 1%
J 0
(-2700 2725);
DISPLAY 0.510638 (-2700 2725);
PAINT SKYBLUE (-2700 2725);
DISPLAY INVISIBLE (-2700 2725);
FORCEPROP 1 LAST LOCATION R175
J 2
(-2775 2625);
DISPLAY 0.702128 (-2775 2625);
PAINT YELLOW (-2775 2625);
FORCEPROP 0 LAST $SEC 1
J 0
(-2850 2675);
DISPLAY 0.680851 (-2850 2675);
PAINT MONO (-2850 2675);
DISPLAY INVISIBLE (-2850 2675);
FORCEPROP 0 LAST CDS_SEC 1
J 0
(-2850 2675);
DISPLAY 1.021277 (-2850 2675);
DISPLAY INVISIBLE (-2850 2675);
FORCEPROP 1 LASTPIN (-2725 2625) $PN 1
J 0
(-2713 2637);
DISPLAY 0.808511 (-2713 2637);
PAINT WHITE (-2713 2637);
DISPLAY INVISIBLE (-2713 2637);
FORCEPROP 1 LASTPIN (-2525 2625) $PN 2
J 0
(-2563 2637);
DISPLAY 0.808511 (-2563 2637);
PAINT WHITE (-2563 2637);
DISPLAY INVISIBLE (-2563 2637);
FORCEADD Q_RES..1
(-2625 2675);
FORCEPROP 1 LAST MATERIAL CHIP
J 2
(-2325 2675);
DISPLAY 0.510638 (-2325 2675);
PAINT SKYBLUE (-2325 2675);
FORCEPROP 1 LAST VALUE 33.2
J 2
(-2450 2675);
DISPLAY 0.510638 (-2450 2675);
PAINT SKYBLUE (-2450 2675);
FORCEPROP 2 LAST CDS_LIB pure_quanta
J 0
(-2625 2675);
DISPLAY INVISIBLE (-2625 2675);
FORCEPROP 1 LAST PATH I331
J 0
(-2675 2825);
DISPLAY 0.978723 (-2675 2825);
PAINT WHITE (-2675 2825);
DISPLAY INVISIBLE (-2675 2825);
FORCEPROP 1 LAST WATTAGE 1/16W
J 2
(-2275 2775);
DISPLAY 0.510638 (-2275 2775);
PAINT SKYBLUE (-2275 2775);
DISPLAY INVISIBLE (-2275 2775);
FORCEPROP 1 LAST PACK_TYPE 0402LF
J 0
(-2650 2725);
DISPLAY 0.510638 (-2650 2725);
PAINT SKYBLUE (-2650 2725);
DISPLAY INVISIBLE (-2650 2725);
FORCEPROP 1 LAST PART_NUMBER CS03322FB03
J 0
(-2725 2750);
DISPLAY 0.510638 (-2725 2750);
PAINT WHITE (-2725 2750);
DISPLAY INVISIBLE (-2725 2750);
FORCEPROP 1 LAST TOLERANCE 1%
J 0
(-2700 2775);
DISPLAY 0.510638 (-2700 2775);
PAINT SKYBLUE (-2700 2775);
DISPLAY INVISIBLE (-2700 2775);
FORCEPROP 1 LAST LOCATION R174
J 2
(-2775 2675);
DISPLAY 0.702128 (-2775 2675);
PAINT YELLOW (-2775 2675);
FORCEPROP 0 LAST $SEC 1
J 0
(-2850 2725);
DISPLAY 0.680851 (-2850 2725);
PAINT MONO (-2850 2725);
DISPLAY INVISIBLE (-2850 2725);
FORCEPROP 0 LAST CDS_SEC 1
J 0
(-2850 2725);
DISPLAY 1.021277 (-2850 2725);
DISPLAY INVISIBLE (-2850 2725);
FORCEPROP 1 LASTPIN (-2725 2675) $PN 1
J 0
(-2713 2687);
DISPLAY 0.808511 (-2713 2687);
PAINT WHITE (-2713 2687);
DISPLAY INVISIBLE (-2713 2687);
FORCEPROP 1 LASTPIN (-2525 2675) $PN 2
J 0
(-2563 2687);
DISPLAY 0.808511 (-2563 2687);
PAINT WHITE (-2563 2687);
DISPLAY INVISIBLE (-2563 2687);
FORCEADD Q_RES..1
(-2625 2575);
FORCEPROP 1 LAST MATERIAL CHIP
J 2
(-2325 2575);
DISPLAY 0.510638 (-2325 2575);
PAINT SKYBLUE (-2325 2575);
FORCEPROP 1 LAST VALUE 33.2
J 2
(-2450 2575);
DISPLAY 0.510638 (-2450 2575);
PAINT SKYBLUE (-2450 2575);
FORCEPROP 2 LAST CDS_LIB pure_quanta
J 0
(-2625 2575);
DISPLAY INVISIBLE (-2625 2575);
FORCEPROP 1 LAST PATH I332
J 0
(-2675 2725);
DISPLAY 0.978723 (-2675 2725);
PAINT WHITE (-2675 2725);
DISPLAY INVISIBLE (-2675 2725);
FORCEPROP 1 LAST WATTAGE 1/16W
J 2
(-2275 2675);
DISPLAY 0.510638 (-2275 2675);
PAINT SKYBLUE (-2275 2675);
DISPLAY INVISIBLE (-2275 2675);
FORCEPROP 1 LAST PACK_TYPE 0402LF
J 0
(-2650 2625);
DISPLAY 0.510638 (-2650 2625);
PAINT SKYBLUE (-2650 2625);
DISPLAY INVISIBLE (-2650 2625);
FORCEPROP 1 LAST PART_NUMBER CS03322FB03
J 0
(-2725 2650);
DISPLAY 0.510638 (-2725 2650);
PAINT WHITE (-2725 2650);
DISPLAY INVISIBLE (-2725 2650);
FORCEPROP 1 LAST TOLERANCE 1%
J 0
(-2700 2675);
DISPLAY 0.510638 (-2700 2675);
PAINT SKYBLUE (-2700 2675);
DISPLAY INVISIBLE (-2700 2675);
FORCEPROP 1 LAST LOCATION R176
J 2
(-2775 2575);
DISPLAY 0.702128 (-2775 2575);
PAINT YELLOW (-2775 2575);
FORCEPROP 0 LAST $SEC 1
J 0
(-2850 2625);
DISPLAY 0.680851 (-2850 2625);
PAINT MONO (-2850 2625);
DISPLAY INVISIBLE (-2850 2625);
FORCEPROP 0 LAST CDS_SEC 1
J 0
(-2850 2625);
DISPLAY 1.021277 (-2850 2625);
DISPLAY INVISIBLE (-2850 2625);
FORCEPROP 1 LASTPIN (-2725 2575) $PN 1
J 0
(-2713 2587);
DISPLAY 0.808511 (-2713 2587);
PAINT WHITE (-2713 2587);
DISPLAY INVISIBLE (-2713 2587);
FORCEPROP 1 LASTPIN (-2525 2575) $PN 2
J 0
(-2563 2587);
DISPLAY 0.808511 (-2563 2587);
PAINT WHITE (-2563 2587);
DISPLAY INVISIBLE (-2563 2587);
FORCEADD Q_RES..1
(-2625 2525);
FORCEPROP 1 LAST MATERIAL CHIP
J 2
(-2325 2525);
DISPLAY 0.510638 (-2325 2525);
PAINT SKYBLUE (-2325 2525);
FORCEPROP 1 LAST VALUE 33.2
J 2
(-2450 2525);
DISPLAY 0.510638 (-2450 2525);
PAINT SKYBLUE (-2450 2525);
FORCEPROP 2 LAST CDS_LIB pure_quanta
J 0
(-2625 2525);
DISPLAY INVISIBLE (-2625 2525);
FORCEPROP 1 LAST PATH I333
J 0
(-2675 2675);
DISPLAY 0.978723 (-2675 2675);
PAINT WHITE (-2675 2675);
DISPLAY INVISIBLE (-2675 2675);
FORCEPROP 1 LAST WATTAGE 1/16W
J 2
(-2275 2625);
DISPLAY 0.510638 (-2275 2625);
PAINT SKYBLUE (-2275 2625);
DISPLAY INVISIBLE (-2275 2625);
FORCEPROP 1 LAST PACK_TYPE 0402LF
J 0
(-2650 2575);
DISPLAY 0.510638 (-2650 2575);
PAINT SKYBLUE (-2650 2575);
DISPLAY INVISIBLE (-2650 2575);
FORCEPROP 1 LAST PART_NUMBER CS03322FB03
J 0
(-2725 2600);
DISPLAY 0.510638 (-2725 2600);
PAINT WHITE (-2725 2600);
DISPLAY INVISIBLE (-2725 2600);
FORCEPROP 1 LAST TOLERANCE 1%
J 0
(-2700 2625);
DISPLAY 0.510638 (-2700 2625);
PAINT SKYBLUE (-2700 2625);
DISPLAY INVISIBLE (-2700 2625);
FORCEPROP 1 LAST LOCATION R724
J 2
(-2775 2525);
DISPLAY 0.702128 (-2775 2525);
PAINT YELLOW (-2775 2525);
FORCEPROP 0 LAST $SEC 1
J 0
(-2850 2575);
DISPLAY 0.680851 (-2850 2575);
PAINT MONO (-2850 2575);
DISPLAY INVISIBLE (-2850 2575);
FORCEPROP 0 LAST CDS_SEC 1
J 0
(-2850 2575);
DISPLAY 1.021277 (-2850 2575);
DISPLAY INVISIBLE (-2850 2575);
FORCEPROP 1 LASTPIN (-2725 2525) $PN 1
J 0
(-2713 2537);
DISPLAY 0.808511 (-2713 2537);
PAINT WHITE (-2713 2537);
DISPLAY INVISIBLE (-2713 2537);
FORCEPROP 1 LASTPIN (-2525 2525) $PN 2
J 0
(-2563 2537);
DISPLAY 0.808511 (-2563 2537);
PAINT WHITE (-2563 2537);
DISPLAY INVISIBLE (-2563 2537);
FORCEADD Q_RES..1
(-2625 2475);
FORCEPROP 1 LAST MATERIAL CHIP
J 2
(-2300 2475);
DISPLAY 0.510638 (-2300 2475);
PAINT SKYBLUE (-2300 2475);
FORCEPROP 1 LAST VALUE 33.2
J 2
(-2450 2475);
DISPLAY 0.510638 (-2450 2475);
PAINT SKYBLUE (-2450 2475);
FORCEPROP 2 LAST CDS_LIB pure_quanta
J 0
(-2625 2475);
DISPLAY INVISIBLE (-2625 2475);
FORCEPROP 1 LAST PATH I334
J 0
(-2675 2625);
DISPLAY 0.978723 (-2675 2625);
PAINT WHITE (-2675 2625);
DISPLAY INVISIBLE (-2675 2625);
FORCEPROP 1 LAST WATTAGE 1/16W
J 2
(-2275 2575);
DISPLAY 0.510638 (-2275 2575);
PAINT SKYBLUE (-2275 2575);
DISPLAY INVISIBLE (-2275 2575);
FORCEPROP 1 LAST PACK_TYPE 0402LF
J 0
(-2650 2525);
DISPLAY 0.510638 (-2650 2525);
PAINT SKYBLUE (-2650 2525);
DISPLAY INVISIBLE (-2650 2525);
FORCEPROP 1 LAST PART_NUMBER CS03322FB03
J 0
(-2725 2550);
DISPLAY 0.510638 (-2725 2550);
PAINT WHITE (-2725 2550);
DISPLAY INVISIBLE (-2725 2550);
FORCEPROP 1 LAST TOLERANCE 1%
J 0
(-2700 2575);
DISPLAY 0.510638 (-2700 2575);
PAINT SKYBLUE (-2700 2575);
DISPLAY INVISIBLE (-2700 2575);
FORCEPROP 1 LAST LOCATION R725
J 2
(-2775 2475);
DISPLAY 0.702128 (-2775 2475);
PAINT YELLOW (-2775 2475);
FORCEPROP 0 LAST $SEC 1
J 0
(-2850 2525);
DISPLAY 0.680851 (-2850 2525);
PAINT MONO (-2850 2525);
DISPLAY INVISIBLE (-2850 2525);
FORCEPROP 0 LAST CDS_SEC 1
J 0
(-2850 2525);
DISPLAY 1.021277 (-2850 2525);
DISPLAY INVISIBLE (-2850 2525);
FORCEPROP 1 LASTPIN (-2725 2475) $PN 1
J 0
(-2713 2487);
DISPLAY 0.808511 (-2713 2487);
PAINT WHITE (-2713 2487);
DISPLAY INVISIBLE (-2713 2487);
FORCEPROP 1 LASTPIN (-2525 2475) $PN 2
J 0
(-2563 2487);
DISPLAY 0.808511 (-2563 2487);
PAINT WHITE (-2563 2487);
DISPLAY INVISIBLE (-2563 2487);
FORCEADD Q_RES..1
(-2625 2300);
FORCEPROP 1 LAST VALUE 0
J 2
(-2400 2300);
DISPLAY 0.510638 (-2400 2300);
PAINT SKYBLUE (-2400 2300);
FORCEPROP 1 LAST PART_NUMBER CS00002JB13
J 0
(-2725 2350);
DISPLAY 0.510638 (-2725 2350);
PAINT WHITE (-2725 2350);
FORCEPROP 1 LAST MATERIAL CHIP
J 0
(-2375 2300);
DISPLAY 0.510638 (-2375 2300);
PAINT SKYBLUE (-2375 2300);
FORCEPROP 2 LAST CDS_LIB pure_quanta
J 0
(-2625 2300);
DISPLAY INVISIBLE (-2625 2300);
FORCEPROP 1 LAST TOLERANCE 5%
J 0
(-2625 2200);
DISPLAY 0.510638 (-2625 2200);
PAINT SKYBLUE (-2625 2200);
DISPLAY INVISIBLE (-2625 2200);
FORCEPROP 1 LAST PATH I336
J 0
(-2675 2450);
DISPLAY 0.978723 (-2675 2450);
PAINT WHITE (-2675 2450);
DISPLAY INVISIBLE (-2675 2450);
FORCEPROP 1 LAST WATTAGE 1/16W
J 2
(-2650 2150);
DISPLAY 0.510638 (-2650 2150);
PAINT SKYBLUE (-2650 2150);
DISPLAY INVISIBLE (-2650 2150);
FORCEPROP 1 LAST PACK_TYPE 0402LF
J 0
(-2375 2150);
DISPLAY 0.510638 (-2375 2150);
PAINT SKYBLUE (-2375 2150);
DISPLAY INVISIBLE (-2375 2150);
FORCEPROP 1 LAST LOCATION R728
J 0
(-2875 2300);
DISPLAY 0.702128 (-2875 2300);
PAINT YELLOW (-2875 2300);
FORCEPROP 1 LASTPIN (-2725 2300) $PN 1
J 0
(-2713 2312);
DISPLAY 0.808511 (-2713 2312);
PAINT WHITE (-2713 2312);
FORCEPROP 1 LASTPIN (-2525 2300) $PN 2
J 0
(-2563 2312);
DISPLAY 0.808511 (-2563 2312);
PAINT WHITE (-2563 2312);
FORCEPROP 2 LAST $SEC 1
J 0
(-2750 2525);
DISPLAY 0.680851 (-2750 2525);
PAINT MONO (-2750 2525);
DISPLAY INVISIBLE (-2750 2525);
FORCEPROP 0 LAST CDS_SEC 1
J 0
(-2750 2525);
DISPLAY 0.680851 (-2750 2525);
PAINT MONO (-2750 2525);
DISPLAY INVISIBLE (-2750 2525);
FORCEADD Q_RES..1
(-2600 1700);
FORCEPROP 1 LAST MATERIAL CHIP
J 2
(-2275 1700);
DISPLAY 0.510638 (-2275 1700);
PAINT SKYBLUE (-2275 1700);
FORCEPROP 1 LAST VALUE 33.2
J 2
(-2400 1700);
DISPLAY 0.510638 (-2400 1700);
PAINT SKYBLUE (-2400 1700);
FORCEPROP 2 LAST CDS_LIB pure_quanta
J 0
(-2600 1700);
DISPLAY INVISIBLE (-2600 1700);
FORCEPROP 1 LAST PATH I339
J 0
(-2650 1850);
DISPLAY 0.978723 (-2650 1850);
PAINT WHITE (-2650 1850);
DISPLAY INVISIBLE (-2650 1850);
FORCEPROP 1 LAST WATTAGE 1/16W
J 2
(-2425 1800);
DISPLAY 0.510638 (-2425 1800);
PAINT SKYBLUE (-2425 1800);
DISPLAY INVISIBLE (-2425 1800);
FORCEPROP 1 LAST PACK_TYPE 0402LF
J 0
(-2400 1800);
DISPLAY 0.510638 (-2400 1800);
PAINT SKYBLUE (-2400 1800);
DISPLAY INVISIBLE (-2400 1800);
FORCEPROP 1 LAST PART_NUMBER CS03322FB03
J 0
(-2600 1875);
DISPLAY 0.510638 (-2600 1875);
PAINT WHITE (-2600 1875);
DISPLAY INVISIBLE (-2600 1875);
FORCEPROP 1 LAST TOLERANCE 1%
J 0
(-2100 1800);
DISPLAY 0.510638 (-2100 1800);
PAINT SKYBLUE (-2100 1800);
DISPLAY INVISIBLE (-2100 1800);
FORCEPROP 1 LAST LOCATION R859
J 2
(-2750 1700);
DISPLAY 0.702128 (-2750 1700);
PAINT YELLOW (-2750 1700);
FORCEPROP 1 LASTPIN (-2700 1700) $PN 1
J 0
(-2688 1712);
DISPLAY 0.808511 (-2688 1712);
PAINT WHITE (-2688 1712);
FORCEPROP 1 LASTPIN (-2500 1700) $PN 2
J 0
(-2538 1712);
DISPLAY 0.808511 (-2538 1712);
PAINT WHITE (-2538 1712);
FORCEPROP 0 LAST $SEC 1
J 0
(-2650 1800);
DISPLAY 0.680851 (-2650 1800);
PAINT MONO (-2650 1800);
DISPLAY INVISIBLE (-2650 1800);
FORCEPROP 0 LAST CDS_SEC 1
J 0
(-2650 1800);
DISPLAY 0.680851 (-2650 1800);
DISPLAY INVISIBLE (-2650 1800);
FORCEADD Q_RES..1
(-2600 1450);
FORCEPROP 1 LAST MATERIAL CHIP
J 0
(-2375 1450);
DISPLAY 0.510638 (-2375 1450);
PAINT SKYBLUE (-2375 1450);
FORCEPROP 1 LAST VALUE 33.2
J 2
(-2400 1450);
DISPLAY 0.510638 (-2400 1450);
PAINT SKYBLUE (-2400 1450);
FORCEPROP 2 LAST CDS_LIB pure_quanta
J 0
(-2600 1450);
DISPLAY INVISIBLE (-2600 1450);
FORCEPROP 1 LAST PATH I342
J 0
(-2650 1600);
DISPLAY 0.978723 (-2650 1600);
PAINT WHITE (-2650 1600);
DISPLAY INVISIBLE (-2650 1600);
FORCEPROP 1 LAST WATTAGE 1/16W
J 2
(-2625 1300);
DISPLAY 0.510638 (-2625 1300);
PAINT SKYBLUE (-2625 1300);
DISPLAY INVISIBLE (-2625 1300);
FORCEPROP 1 LAST PACK_TYPE 0402LF
J 0
(-2350 1300);
DISPLAY 0.510638 (-2350 1300);
PAINT SKYBLUE (-2350 1300);
DISPLAY INVISIBLE (-2350 1300);
FORCEPROP 1 LAST PART_NUMBER CS03322FB03
J 0
(-2475 1500);
DISPLAY 0.510638 (-2475 1500);
PAINT WHITE (-2475 1500);
DISPLAY INVISIBLE (-2475 1500);
FORCEPROP 1 LAST TOLERANCE 1%
J 0
(-2475 1450);
DISPLAY 0.510638 (-2475 1450);
PAINT SKYBLUE (-2475 1450);
DISPLAY INVISIBLE (-2475 1450);
FORCEPROP 1 LAST LOCATION R864
J 2
(-2750 1450);
DISPLAY 0.702128 (-2750 1450);
PAINT YELLOW (-2750 1450);
FORCEPROP 1 LASTPIN (-2700 1450) $PN 1
J 0
(-2688 1462);
DISPLAY 0.808511 (-2688 1462);
PAINT WHITE (-2688 1462);
FORCEPROP 1 LASTPIN (-2500 1450) $PN 2
J 0
(-2535 1460);
DISPLAY 0.808511 (-2535 1460);
PAINT WHITE (-2535 1460);
FORCEPROP 2 LAST $SEC 1
J 0
(-2650 1650);
DISPLAY 0.680851 (-2650 1650);
PAINT MONO (-2650 1650);
DISPLAY INVISIBLE (-2650 1650);
FORCEPROP 0 LAST CDS_SEC 1
J 0
(-2650 1650);
DISPLAY 0.680851 (-2650 1650);
PAINT MONO (-2650 1650);
DISPLAY INVISIBLE (-2650 1650);
FORCEADD OFFPAGE..1
(-4050 2675);
FORCEPROP 2 LAST $XR0 13 
J 0
(-4301 2675);
DISPLAY 0.638298 (-4301 2675);
PAINT MONO (-4301 2675);
FORCEPROP 2 LAST CDS_LIB standard
J 0
(-4050 2675);
DISPLAY INVISIBLE (-4050 2675);
FORCEPROP 1 LAST OFFPAGE TRUE
J 0
(-3725 2550);
DISPLAY 0.872340 (-3725 2550);
PAINT GREEN (-3725 2550);
DISPLAY INVISIBLE (-3725 2550);
FORCEPROP 1 LAST COMMENT_BODY TRUE
J 0
(-3925 2575);
DISPLAY 0.872340 (-3925 2575);
PAINT PEACH (-3925 2575);
DISPLAY INVISIBLE (-3925 2575);
FORCEPROP 2 LAST PATH I343
J 0
(-4300 2725);
DISPLAY 0.680851 (-4300 2725);
DISPLAY INVISIBLE (-4300 2725);
FORCEADD OFFPAGE..1
(-4050 2625);
FORCEPROP 2 LAST $XR0 13 
J 0
(-4301 2625);
DISPLAY 0.638298 (-4301 2625);
PAINT MONO (-4301 2625);
FORCEPROP 2 LAST CDS_LIB standard
J 0
(-4050 2625);
DISPLAY INVISIBLE (-4050 2625);
FORCEPROP 1 LAST OFFPAGE TRUE
J 0
(-3725 2500);
DISPLAY 0.872340 (-3725 2500);
PAINT GREEN (-3725 2500);
DISPLAY INVISIBLE (-3725 2500);
FORCEPROP 1 LAST COMMENT_BODY TRUE
J 0
(-3925 2525);
DISPLAY 0.872340 (-3925 2525);
PAINT PEACH (-3925 2525);
DISPLAY INVISIBLE (-3925 2525);
FORCEPROP 2 LAST PATH I344
J 0
(-4300 2675);
DISPLAY 0.680851 (-4300 2675);
DISPLAY INVISIBLE (-4300 2675);
FORCEADD OFFPAGE..5
(-4050 2575);
FORCEPROP 2 LAST $XR0 13 
J 0
(-4274 2575);
DISPLAY 0.638298 (-4274 2575);
PAINT MONO (-4274 2575);
FORCEPROP 2 LAST CDS_LIB standard
J 0
(-4050 2575);
DISPLAY INVISIBLE (-4050 2575);
FORCEPROP 1 LAST OFFPAGE TRUE
J 0
(-3725 2450);
DISPLAY 0.872340 (-3725 2450);
PAINT GREEN (-3725 2450);
DISPLAY INVISIBLE (-3725 2450);
FORCEPROP 1 LAST COMMENT_BODY TRUE
J 0
(-3950 2500);
DISPLAY 0.872340 (-3950 2500);
PAINT PEACH (-3950 2500);
DISPLAY INVISIBLE (-3950 2500);
FORCEPROP 2 LAST PATH I345
J 0
(-4250 2625);
DISPLAY 0.680851 (-4250 2625);
DISPLAY INVISIBLE (-4250 2625);
FORCEADD OFFPAGE..1
(-4050 2525);
FORCEPROP 2 LAST $XR0 13 
J 0
(-4301 2525);
DISPLAY 0.638298 (-4301 2525);
PAINT MONO (-4301 2525);
FORCEPROP 2 LAST CDS_LIB standard
J 0
(-4050 2525);
DISPLAY INVISIBLE (-4050 2525);
FORCEPROP 1 LAST OFFPAGE TRUE
J 0
(-3725 2400);
DISPLAY 0.872340 (-3725 2400);
PAINT GREEN (-3725 2400);
DISPLAY INVISIBLE (-3725 2400);
FORCEPROP 1 LAST COMMENT_BODY TRUE
J 0
(-3925 2425);
DISPLAY 0.872340 (-3925 2425);
PAINT PEACH (-3925 2425);
DISPLAY INVISIBLE (-3925 2425);
FORCEPROP 2 LAST PATH I346
J 0
(-4300 2575);
DISPLAY 0.680851 (-4300 2575);
DISPLAY INVISIBLE (-4300 2575);
FORCEADD OFFPAGE..1
(-4050 2475);
FORCEPROP 2 LAST $XR0 13 
J 0
(-4301 2475);
DISPLAY 0.638298 (-4301 2475);
PAINT MONO (-4301 2475);
FORCEPROP 2 LAST CDS_LIB standard
J 0
(-4050 2475);
DISPLAY INVISIBLE (-4050 2475);
FORCEPROP 1 LAST OFFPAGE TRUE
J 0
(-3725 2350);
DISPLAY 0.872340 (-3725 2350);
PAINT GREEN (-3725 2350);
DISPLAY INVISIBLE (-3725 2350);
FORCEPROP 1 LAST COMMENT_BODY TRUE
J 0
(-3925 2375);
DISPLAY 0.872340 (-3925 2375);
PAINT PEACH (-3925 2375);
DISPLAY INVISIBLE (-3925 2375);
FORCEPROP 2 LAST PATH I347
J 0
(-4300 2525);
DISPLAY 0.680851 (-4300 2525);
DISPLAY INVISIBLE (-4300 2525);
FORCEADD OFFPAGE..1
(-4050 2300);
FORCEPROP 2 LAST $XR0 13 
J 0
(-4301 2300);
DISPLAY 0.638298 (-4301 2300);
PAINT MONO (-4301 2300);
FORCEPROP 2 LAST CDS_LIB standard
J 0
(-4050 2300);
DISPLAY INVISIBLE (-4050 2300);
FORCEPROP 1 LAST OFFPAGE TRUE
J 0
(-3725 2175);
DISPLAY 0.872340 (-3725 2175);
PAINT GREEN (-3725 2175);
DISPLAY INVISIBLE (-3725 2175);
FORCEPROP 1 LAST COMMENT_BODY TRUE
J 0
(-3925 2200);
DISPLAY 0.872340 (-3925 2200);
PAINT PEACH (-3925 2200);
DISPLAY INVISIBLE (-3925 2200);
FORCEPROP 2 LAST PATH I349
J 0
(-4300 2350);
DISPLAY 0.680851 (-4300 2350);
DISPLAY INVISIBLE (-4300 2350);
FORCEADD OFFPAGE..1
(-4050 1700);
FORCEPROP 2 LAST $XR1 46 
J 0
(-4391 1700);
DISPLAY 0.638298 (-4391 1700);
PAINT MONO (-4391 1700);
FORCEPROP 2 LAST $XR0 10 
J 0
(-4301 1700);
DISPLAY 0.638298 (-4301 1700);
PAINT MONO (-4301 1700);
FORCEPROP 2 LAST CDS_LIB standard
J 0
(-4050 1700);
DISPLAY INVISIBLE (-4050 1700);
FORCEPROP 1 LAST OFFPAGE TRUE
J 0
(-3725 1575);
DISPLAY 0.872340 (-3725 1575);
PAINT GREEN (-3725 1575);
DISPLAY INVISIBLE (-3725 1575);
FORCEPROP 1 LAST COMMENT_BODY TRUE
J 0
(-3925 1600);
DISPLAY 0.872340 (-3925 1600);
PAINT PEACH (-3925 1600);
DISPLAY INVISIBLE (-3925 1600);
FORCEPROP 2 LAST PATH I350
J 0
(-4300 1750);
DISPLAY 0.680851 (-4300 1750);
DISPLAY INVISIBLE (-4300 1750);
FORCEADD OFFPAGE..1
(-4050 1650);
FORCEPROP 2 LAST $XR1 46 
J 0
(-4391 1650);
DISPLAY 0.638298 (-4391 1650);
PAINT MONO (-4391 1650);
FORCEPROP 2 LAST $XR0 10 
J 0
(-4301 1650);
DISPLAY 0.638298 (-4301 1650);
PAINT MONO (-4301 1650);
FORCEPROP 2 LAST CDS_LIB standard
J 0
(-4050 1650);
DISPLAY INVISIBLE (-4050 1650);
FORCEPROP 1 LAST OFFPAGE TRUE
J 0
(-3725 1525);
DISPLAY 0.872340 (-3725 1525);
PAINT GREEN (-3725 1525);
DISPLAY INVISIBLE (-3725 1525);
FORCEPROP 1 LAST COMMENT_BODY TRUE
J 0
(-3925 1550);
DISPLAY 0.872340 (-3925 1550);
PAINT PEACH (-3925 1550);
DISPLAY INVISIBLE (-3925 1550);
FORCEPROP 2 LAST PATH I351
J 0
(-4300 1700);
DISPLAY 0.680851 (-4300 1700);
DISPLAY INVISIBLE (-4300 1700);
FORCEADD OFFPAGE..5
(-4050 1600);
FORCEPROP 2 LAST $XR0 46 
J 0
(-4274 1600);
DISPLAY 0.638298 (-4274 1600);
PAINT MONO (-4274 1600);
FORCEPROP 2 LAST $XR1 10 
J 0
(-4364 1600);
DISPLAY 0.638298 (-4364 1600);
PAINT MONO (-4364 1600);
FORCEPROP 2 LAST CDS_LIB standard
J 0
(-4050 1600);
DISPLAY INVISIBLE (-4050 1600);
FORCEPROP 1 LAST OFFPAGE TRUE
J 0
(-3725 1475);
DISPLAY 0.872340 (-3725 1475);
PAINT GREEN (-3725 1475);
DISPLAY INVISIBLE (-3725 1475);
FORCEPROP 1 LAST COMMENT_BODY TRUE
J 0
(-3950 1525);
DISPLAY 0.872340 (-3950 1525);
PAINT PEACH (-3950 1525);
DISPLAY INVISIBLE (-3950 1525);
FORCEPROP 2 LAST PATH I352
J 0
(-4250 1650);
DISPLAY 0.680851 (-4250 1650);
DISPLAY INVISIBLE (-4250 1650);
FORCEADD OFFPAGE..1
(-4050 1550);
FORCEPROP 2 LAST $XR0 10 
J 0
(-4301 1550);
DISPLAY 0.638298 (-4301 1550);
PAINT MONO (-4301 1550);
FORCEPROP 2 LAST CDS_LIB standard
J 0
(-4050 1550);
DISPLAY INVISIBLE (-4050 1550);
FORCEPROP 1 LAST OFFPAGE TRUE
J 0
(-3725 1425);
DISPLAY 0.872340 (-3725 1425);
PAINT GREEN (-3725 1425);
DISPLAY INVISIBLE (-3725 1425);
FORCEPROP 1 LAST COMMENT_BODY TRUE
J 0
(-3925 1450);
DISPLAY 0.872340 (-3925 1450);
PAINT PEACH (-3925 1450);
DISPLAY INVISIBLE (-3925 1450);
FORCEPROP 2 LAST PATH I353
J 0
(-4300 1600);
DISPLAY 0.680851 (-4300 1600);
DISPLAY INVISIBLE (-4300 1600);
FORCEADD OFFPAGE..1
(-4050 1500);
FORCEPROP 2 LAST $XR0 10 
J 0
(-4301 1500);
DISPLAY 0.638298 (-4301 1500);
PAINT MONO (-4301 1500);
FORCEPROP 2 LAST CDS_LIB standard
J 0
(-4050 1500);
DISPLAY INVISIBLE (-4050 1500);
FORCEPROP 1 LAST OFFPAGE TRUE
J 0
(-3725 1375);
DISPLAY 0.872340 (-3725 1375);
PAINT GREEN (-3725 1375);
DISPLAY INVISIBLE (-3725 1375);
FORCEPROP 1 LAST COMMENT_BODY TRUE
J 0
(-3925 1400);
DISPLAY 0.872340 (-3925 1400);
PAINT PEACH (-3925 1400);
DISPLAY INVISIBLE (-3925 1400);
FORCEPROP 2 LAST PATH I354
J 0
(-4300 1550);
DISPLAY 0.680851 (-4300 1550);
DISPLAY INVISIBLE (-4300 1550);
FORCEADD OFFPAGE..1
(-4050 1450);
FORCEPROP 2 LAST $XR0 10 
J 0
(-4301 1450);
DISPLAY 0.638298 (-4301 1450);
PAINT MONO (-4301 1450);
FORCEPROP 2 LAST CDS_LIB standard
J 0
(-4050 1450);
DISPLAY INVISIBLE (-4050 1450);
FORCEPROP 1 LAST OFFPAGE TRUE
J 0
(-3725 1325);
DISPLAY 0.872340 (-3725 1325);
PAINT GREEN (-3725 1325);
DISPLAY INVISIBLE (-3725 1325);
FORCEPROP 1 LAST COMMENT_BODY TRUE
J 0
(-3925 1350);
DISPLAY 0.872340 (-3925 1350);
PAINT PEACH (-3925 1350);
DISPLAY INVISIBLE (-3925 1350);
FORCEPROP 2 LAST PATH I355
J 0
(-4300 1500);
DISPLAY 0.680851 (-4300 1500);
DISPLAY INVISIBLE (-4300 1500);
FORCEADD OFFPAGE..2
(-650 225);
FORCEPROP 2 LAST $XR0 44 
J 0
(-461 225);
DISPLAY 0.638298 (-461 225);
PAINT MONO (-461 225);
FORCEPROP 2 LAST CDS_LIB standard
J 0
(-650 225);
DISPLAY INVISIBLE (-650 225);
FORCEPROP 1 LAST OFFPAGE TRUE
J 0
(-325 100);
DISPLAY 0.872340 (-325 100);
PAINT GREEN (-325 100);
DISPLAY INVISIBLE (-325 100);
FORCEPROP 1 LAST COMMENT_BODY TRUE
J 0
(-695 130);
DISPLAY 0.872340 (-695 130);
PAINT PEACH (-695 130);
DISPLAY INVISIBLE (-695 130);
FORCEPROP 2 LAST PATH I356
J 0
(-475 300);
DISPLAY 0.680851 (-475 300);
DISPLAY INVISIBLE (-475 300);
FORCEADD OFFPAGE..1
(-4100 225);
FORCEPROP 2 LAST $XR0 13 
J 0
(-4321 225);
DISPLAY 0.638298 (-4321 225);
PAINT MONO (-4321 225);
FORCEPROP 2 LAST CDS_LIB standard
J 0
(-4100 225);
DISPLAY INVISIBLE (-4100 225);
FORCEPROP 1 LAST OFFPAGE TRUE
J 0
(-3775 100);
DISPLAY 0.872340 (-3775 100);
PAINT GREEN (-3775 100);
DISPLAY INVISIBLE (-3775 100);
FORCEPROP 1 LAST COMMENT_BODY TRUE
J 0
(-3975 125);
DISPLAY 0.872340 (-3975 125);
PAINT PEACH (-3975 125);
DISPLAY INVISIBLE (-3975 125);
FORCEPROP 2 LAST PATH I358
J 0
(-4350 275);
DISPLAY 0.680851 (-4350 275);
DISPLAY INVISIBLE (-4350 275);
FORCEADD OFFPAGE..2
(-650 -125);
FORCEPROP 2 LAST $XR0 46 
J 0
(-461 -125);
DISPLAY 0.638298 (-461 -125);
PAINT MONO (-461 -125);
FORCEPROP 2 LAST CDS_LIB standard
J 0
(-650 -125);
DISPLAY INVISIBLE (-650 -125);
FORCEPROP 1 LAST OFFPAGE TRUE
J 0
(-325 -250);
DISPLAY 0.872340 (-325 -250);
PAINT GREEN (-325 -250);
DISPLAY INVISIBLE (-325 -250);
FORCEPROP 1 LAST COMMENT_BODY TRUE
J 0
(-695 -220);
DISPLAY 0.872340 (-695 -220);
PAINT PEACH (-695 -220);
DISPLAY INVISIBLE (-695 -220);
FORCEPROP 2 LAST PATH I359
J 0
(-450 -75);
DISPLAY 0.680851 (-450 -75);
DISPLAY INVISIBLE (-450 -75);
FORCEADD Q_RES..1
(-2425 -125);
FORCEPROP 1 LAST VALUE 33.2
J 0
(-2300 -125);
DISPLAY 0.510638 (-2300 -125);
PAINT SKYBLUE (-2300 -125);
FORCEPROP 1 LAST MATERIAL CHIP
J 0
(-2175 -125);
DISPLAY 0.510638 (-2175 -125);
PAINT SKYBLUE (-2175 -125);
FORCEPROP 1 LAST TOLERANCE 1%
J 0
(-2300 -125);
DISPLAY 0.510638 (-2300 -125);
PAINT SKYBLUE (-2300 -125);
DISPLAY INVISIBLE (-2300 -125);
FORCEPROP 1 LAST PART_NUMBER CS03322FB03
J 0
(-2300 -75);
DISPLAY 0.510638 (-2300 -75);
PAINT WHITE (-2300 -75);
DISPLAY INVISIBLE (-2300 -75);
FORCEPROP 1 LAST PACK_TYPE 0402LF
J 0
(-2175 -275);
DISPLAY 0.510638 (-2175 -275);
PAINT SKYBLUE (-2175 -275);
DISPLAY INVISIBLE (-2175 -275);
FORCEPROP 1 LAST WATTAGE 1/16W
J 2
(-2450 -275);
DISPLAY 0.510638 (-2450 -275);
PAINT SKYBLUE (-2450 -275);
DISPLAY INVISIBLE (-2450 -275);
FORCEPROP 1 LAST PATH I360
J 0
(-2475 25);
DISPLAY 0.978723 (-2475 25);
PAINT WHITE (-2475 25);
DISPLAY INVISIBLE (-2475 25);
FORCEPROP 2 LAST CDS_LIB pure_quanta
J 0
(-2425 -125);
DISPLAY INVISIBLE (-2425 -125);
FORCEPROP 1 LAST LOCATION R594
J 0
(-2725 -125);
DISPLAY 0.702128 (-2725 -125);
PAINT YELLOW (-2725 -125);
FORCEPROP 1 LASTPIN (-2525 -125) $PN 1
J 0
(-2513 -113);
DISPLAY 0.808511 (-2513 -113);
PAINT WHITE (-2513 -113);
FORCEPROP 1 LASTPIN (-2325 -125) $PN 2
J 0
(-2360 -115);
DISPLAY 0.808511 (-2360 -115);
PAINT WHITE (-2360 -115);
FORCEPROP 2 LAST $SEC 1
J 0
(-2475 75);
DISPLAY 0.680851 (-2475 75);
PAINT MONO (-2475 75);
DISPLAY INVISIBLE (-2475 75);
FORCEPROP 0 LAST CDS_SEC 1
J 0
(-2475 75);
DISPLAY 0.680851 (-2475 75);
PAINT MONO (-2475 75);
DISPLAY INVISIBLE (-2475 75);
FORCEADD OFFPAGE..1
(-4100 -125);
FORCEPROP 2 LAST $XR0 10 
J 0
(-4321 -125);
DISPLAY 0.638298 (-4321 -125);
PAINT MONO (-4321 -125);
FORCEPROP 2 LAST CDS_LIB standard
J 0
(-4100 -125);
DISPLAY INVISIBLE (-4100 -125);
FORCEPROP 1 LAST OFFPAGE TRUE
J 0
(-3775 -250);
DISPLAY 0.872340 (-3775 -250);
PAINT GREEN (-3775 -250);
DISPLAY INVISIBLE (-3775 -250);
FORCEPROP 1 LAST COMMENT_BODY TRUE
J 0
(-3975 -225);
DISPLAY 0.872340 (-3975 -225);
PAINT PEACH (-3975 -225);
DISPLAY INVISIBLE (-3975 -225);
FORCEPROP 2 LAST PATH I361
J 0
(-4300 -75);
DISPLAY 0.680851 (-4300 -75);
DISPLAY INVISIBLE (-4300 -75);
FORCEADD Q_RES..1
(-2600 1650);
FORCEPROP 1 LAST MATERIAL CHIP
J 0
(-2400 1650);
DISPLAY 0.510638 (-2400 1650);
PAINT SKYBLUE (-2400 1650);
FORCEPROP 1 LAST PART_NUMBER CS02202FB02
J 0
(-2275 1650);
DISPLAY 0.510638 (-2275 1650);
FORCEPROP 1 LAST VALUE 22
J 2
(-2450 1650);
DISPLAY 0.510638 (-2450 1650);
PAINT SKYBLUE (-2450 1650);
FORCEPROP 2 LAST CDS_LIB pure_quanta
J 0
(-2600 1650);
DISPLAY INVISIBLE (-2600 1650);
FORCEPROP 1 LAST PATH I362
J 0
(-2650 1800);
DISPLAY 0.978723 (-2650 1800);
PAINT WHITE (-2650 1800);
DISPLAY INVISIBLE (-2650 1800);
FORCEPROP 1 LAST TOLERANCE 1%
J 0
(-2600 1550);
DISPLAY 0.510638 (-2600 1550);
DISPLAY INVISIBLE (-2600 1550);
FORCEPROP 1 LAST WATTAGE 1/16W
J 2
(-2625 1500);
DISPLAY 0.510638 (-2625 1500);
DISPLAY INVISIBLE (-2625 1500);
FORCEPROP 1 LAST PACK_TYPE 0402LF
J 0
(-2350 1500);
DISPLAY 0.510638 (-2350 1500);
DISPLAY INVISIBLE (-2350 1500);
FORCEPROP 1 LAST LOCATION R860
J 0
(-2850 1650);
DISPLAY 0.808511 (-2850 1650);
PAINT YELLOW (-2850 1650);
FORCEPROP 1 LASTPIN (-2700 1650) $PN 1
J 0
(-2688 1662);
DISPLAY 0.787234 (-2688 1662);
PAINT MONO (-2688 1662);
FORCEPROP 1 LASTPIN (-2500 1650) $PN 2
J 0
(-2538 1662);
DISPLAY 0.787234 (-2538 1662);
PAINT MONO (-2538 1662);
FORCEPROP 0 LAST $SEC 1
J 0
(-2850 1700);
DISPLAY 0.680851 (-2850 1700);
PAINT MONO (-2850 1700);
DISPLAY INVISIBLE (-2850 1700);
FORCEPROP 0 LAST CDS_SEC 1
J 0
(-2850 1700);
DISPLAY 0.680851 (-2850 1700);
DISPLAY INVISIBLE (-2850 1700);
FORCEADD Q_RES..1
(-2600 1600);
FORCEPROP 1 LAST MATERIAL CHIP
J 0
(-2400 1600);
DISPLAY 0.510638 (-2400 1600);
PAINT SKYBLUE (-2400 1600);
FORCEPROP 1 LAST VALUE 22
J 2
(-2450 1600);
DISPLAY 0.510638 (-2450 1600);
PAINT SKYBLUE (-2450 1600);
FORCEPROP 2 LAST CDS_LIB pure_quanta
J 0
(-2600 1600);
DISPLAY INVISIBLE (-2600 1600);
FORCEPROP 1 LAST PART_NUMBER CS02202FB02
J 0
(-2600 1650);
DISPLAY 0.510638 (-2600 1650);
DISPLAY INVISIBLE (-2600 1650);
FORCEPROP 1 LAST TOLERANCE 1%
J 0
(-2600 1500);
DISPLAY 0.510638 (-2600 1500);
DISPLAY INVISIBLE (-2600 1500);
FORCEPROP 1 LAST WATTAGE 1/16W
J 2
(-2625 1450);
DISPLAY 0.510638 (-2625 1450);
DISPLAY INVISIBLE (-2625 1450);
FORCEPROP 1 LAST PACK_TYPE 0402LF
J 0
(-2350 1450);
DISPLAY 0.510638 (-2350 1450);
DISPLAY INVISIBLE (-2350 1450);
FORCEPROP 1 LAST PATH I363
J 0
(-2650 1750);
DISPLAY 0.978723 (-2650 1750);
PAINT WHITE (-2650 1750);
DISPLAY INVISIBLE (-2650 1750);
FORCEPROP 1 LAST LOCATION R861
J 0
(-2850 1600);
DISPLAY 0.808511 (-2850 1600);
PAINT YELLOW (-2850 1600);
FORCEPROP 1 LASTPIN (-2700 1600) $PN 1
J 0
(-2688 1612);
DISPLAY 0.787234 (-2688 1612);
PAINT MONO (-2688 1612);
FORCEPROP 1 LASTPIN (-2500 1600) $PN 2
J 0
(-2538 1612);
DISPLAY 0.787234 (-2538 1612);
PAINT MONO (-2538 1612);
FORCEPROP 0 LAST $SEC 1
J 0
(-2850 1650);
DISPLAY 0.680851 (-2850 1650);
PAINT MONO (-2850 1650);
DISPLAY INVISIBLE (-2850 1650);
FORCEPROP 0 LAST CDS_SEC 1
J 0
(-2850 1650);
DISPLAY 0.680851 (-2850 1650);
DISPLAY INVISIBLE (-2850 1650);
FORCEADD Q_RES..1
(-2600 1550);
FORCEPROP 1 LAST MATERIAL CHIP
J 0
(-2400 1550);
DISPLAY 0.510638 (-2400 1550);
PAINT SKYBLUE (-2400 1550);
FORCEPROP 1 LAST VALUE 22
J 2
(-2450 1550);
DISPLAY 0.510638 (-2450 1550);
PAINT SKYBLUE (-2450 1550);
FORCEPROP 1 LAST PART_NUMBER CS02202FB02
J 0
(-2600 1600);
DISPLAY 0.510638 (-2600 1600);
DISPLAY INVISIBLE (-2600 1600);
FORCEPROP 1 LAST TOLERANCE 1%
J 0
(-2600 1450);
DISPLAY 0.510638 (-2600 1450);
DISPLAY INVISIBLE (-2600 1450);
FORCEPROP 1 LAST WATTAGE 1/16W
J 2
(-2625 1400);
DISPLAY 0.510638 (-2625 1400);
DISPLAY INVISIBLE (-2625 1400);
FORCEPROP 1 LAST PACK_TYPE 0402LF
J 0
(-2350 1400);
DISPLAY 0.510638 (-2350 1400);
DISPLAY INVISIBLE (-2350 1400);
FORCEPROP 1 LAST PATH I364
J 0
(-2650 1700);
DISPLAY 0.978723 (-2650 1700);
PAINT WHITE (-2650 1700);
DISPLAY INVISIBLE (-2650 1700);
FORCEPROP 2 LAST CDS_LIB pure_quanta
J 0
(-2600 1550);
DISPLAY INVISIBLE (-2600 1550);
FORCEPROP 1 LAST LOCATION R862
J 0
(-2850 1550);
DISPLAY 0.808511 (-2850 1550);
PAINT YELLOW (-2850 1550);
FORCEPROP 1 LASTPIN (-2700 1550) $PN 1
J 0
(-2688 1562);
DISPLAY 0.787234 (-2688 1562);
PAINT MONO (-2688 1562);
FORCEPROP 1 LASTPIN (-2500 1550) $PN 2
J 0
(-2538 1562);
DISPLAY 0.787234 (-2538 1562);
PAINT MONO (-2538 1562);
FORCEPROP 0 LAST $SEC 1
J 0
(-2850 1600);
DISPLAY 0.680851 (-2850 1600);
PAINT MONO (-2850 1600);
DISPLAY INVISIBLE (-2850 1600);
FORCEPROP 0 LAST CDS_SEC 1
J 0
(-2850 1600);
DISPLAY 0.680851 (-2850 1600);
DISPLAY INVISIBLE (-2850 1600);
FORCEADD Q_RES..1
(-2600 1500);
FORCEPROP 1 LAST MATERIAL CHIP
J 0
(-2400 1500);
DISPLAY 0.510638 (-2400 1500);
PAINT SKYBLUE (-2400 1500);
FORCEPROP 1 LAST VALUE 22
J 2
(-2450 1500);
DISPLAY 0.510638 (-2450 1500);
PAINT SKYBLUE (-2450 1500);
FORCEPROP 2 LAST CDS_LIB pure_quanta
J 0
(-2600 1500);
DISPLAY INVISIBLE (-2600 1500);
FORCEPROP 1 LAST PATH I365
J 0
(-2650 1650);
DISPLAY 0.978723 (-2650 1650);
PAINT WHITE (-2650 1650);
DISPLAY INVISIBLE (-2650 1650);
FORCEPROP 1 LAST PACK_TYPE 0402LF
J 0
(-2350 1350);
DISPLAY 0.510638 (-2350 1350);
DISPLAY INVISIBLE (-2350 1350);
FORCEPROP 1 LAST WATTAGE 1/16W
J 2
(-2625 1350);
DISPLAY 0.510638 (-2625 1350);
DISPLAY INVISIBLE (-2625 1350);
FORCEPROP 1 LAST TOLERANCE 1%
J 0
(-2600 1400);
DISPLAY 0.510638 (-2600 1400);
DISPLAY INVISIBLE (-2600 1400);
FORCEPROP 1 LAST PART_NUMBER CS02202FB02
J 0
(-2600 1550);
DISPLAY 0.510638 (-2600 1550);
DISPLAY INVISIBLE (-2600 1550);
FORCEPROP 1 LAST LOCATION R863
J 0
(-2850 1500);
DISPLAY 0.808511 (-2850 1500);
PAINT YELLOW (-2850 1500);
FORCEPROP 1 LASTPIN (-2700 1500) $PN 1
J 0
(-2688 1512);
DISPLAY 0.787234 (-2688 1512);
PAINT MONO (-2688 1512);
FORCEPROP 1 LASTPIN (-2500 1500) $PN 2
J 0
(-2538 1512);
DISPLAY 0.787234 (-2538 1512);
PAINT MONO (-2538 1512);
FORCEPROP 0 LAST $SEC 1
J 0
(-2850 1550);
DISPLAY 0.680851 (-2850 1550);
PAINT MONO (-2850 1550);
DISPLAY INVISIBLE (-2850 1550);
FORCEPROP 0 LAST CDS_SEC 1
J 0
(-2850 1550);
DISPLAY 0.680851 (-2850 1550);
DISPLAY INVISIBLE (-2850 1550);
FORCEADD Q_RES..1
(-2425 225);
FORCEPROP 1 LAST VALUE 68.1
J 2
(-2200 225);
DISPLAY 0.638298 (-2200 225);
PAINT SKYBLUE (-2200 225);
FORCEPROP 1 LAST PART_NUMBER CS06812FB03
J 0
(-2475 325);
DISPLAY 0.638298 (-2475 325);
FORCEPROP 1 LAST MATERIAL CHIP
J 0
(-2175 225);
DISPLAY 0.638298 (-2175 225);
PAINT SKYBLUE (-2175 225);
FORCEPROP 1 LAST PACK_TYPE 0402LF
J 0
(-2175 75);
DISPLAY 0.638298 (-2175 75);
DISPLAY INVISIBLE (-2175 75);
FORCEPROP 1 LAST TOLERANCE 1%
J 0
(-2425 125);
DISPLAY 0.638298 (-2425 125);
DISPLAY INVISIBLE (-2425 125);
FORCEPROP 1 LAST WATTAGE 1/16W
J 2
(-2450 75);
DISPLAY 0.638298 (-2450 75);
DISPLAY INVISIBLE (-2450 75);
FORCEPROP 1 LAST PATH I366
J 0
(-2475 375);
DISPLAY 0.978723 (-2475 375);
PAINT WHITE (-2475 375);
DISPLAY INVISIBLE (-2475 375);
FORCEPROP 2 LAST CDS_LIB pure_quanta
J 0
(-2425 225);
DISPLAY INVISIBLE (-2425 225);
FORCEPROP 1 LAST LOCATION R852
J 0
(-2700 225);
DISPLAY 0.787234 (-2700 225);
FORCEPROP 1 LASTPIN (-2525 225) $PN 1
J 0
(-2513 237);
DISPLAY 0.787234 (-2513 237);
PAINT MONO (-2513 237);
FORCEPROP 1 LASTPIN (-2325 225) $PN 2
J 0
(-2363 237);
DISPLAY 0.787234 (-2363 237);
PAINT MONO (-2363 237);
FORCEPROP 0 LAST $SEC 1
J 0
(-2475 375);
DISPLAY 0.680851 (-2475 375);
PAINT MONO (-2475 375);
DISPLAY INVISIBLE (-2475 375);
FORCEPROP 0 LAST CDS_SEC 1
J 0
(-2475 375);
DISPLAY 0.680851 (-2475 375);
DISPLAY INVISIBLE (-2475 375);
FORCEADD QUANTA_TITLE_BLOCK_C..1
(4775 -2375);
FORCEPROP 0 LAST CDS_CON_LAST_MODIFIED Fri Aug 25 17:25:46 2023
J 0
(2890 -2360);
DISPLAY INVISIBLE (2890 -2360);
FORCEPROP 2 LAST Q_DEPT 
J 1
(1012 -2326);
DISPLAY 1.957447 (1012 -2326);
PAINT GREEN (1012 -2326);
FORCEPROP 1 LAST CUSTOM_TXT_CDS <CON_LAST_MODIFIED>
J 0
(2890 -2360);
DISPLAY 0.978723 (2890 -2360);
FORCEPROP 2 LAST CUSTOM_TXT_CDS <XR_PAGE_TITLE>
J 0
(-3115 2875);
DISPLAY 0.638298 (-3115 2875);
PAINT PINK (-3115 2875);
DISPLAY INVISIBLE (-3115 2875);
FORCEPROP 1 LAST CUSTOM_TXT_CDS <NAME_2>
J 0
(1600 -2325);
FORCEPROP 1 LAST CUSTOM_TXT_CDS <NAME_1>
J 0
(1600 -2200);
FORCEPROP 1 LAST CUSTOM_TXT_CDS <Q_NUMBER>
J 0
(3372 -2272);
DISPLAY 1.212766 (3372 -2272);
FORCEPROP 1 LAST CUSTOM_TXT_CDS <Q_PROJ>
J 0
(2393 -2273);
DISPLAY 1.212766 (2393 -2273);
FORCEPROP 1 LAST CUSTOM_TXT_CDS <Q_REV>
J 0
(4591 -2272);
DISPLAY 1.212766 (4591 -2272);
FORCEPROP 1 LAST CUSTOM_TXT_CDS <CON_PAGE_NUM> OF <CON_TOTAL_PAGES>
J 0
(4329 -2357);
DISPLAY 0.978723 (4329 -2357);
FORCEPROP 1 LAST Q_TITLE SPI - BIOS FLASH MEMORY MUX
J 0
(-4566 -2349);
DISPLAY 2.446809 (-4566 -2349);
PAINT GREEN (-4566 -2349);
FORCEPROP 2 LAST CDS_XR_PAGE_TITLE CR-44 : @SCM_LIB.SCM(SCH_1):PAGE44
J 0
(-3115 2875);
DISPLAY 0.638298 (-3115 2875);
PAINT PINK (-3115 2875);
DISPLAY INVISIBLE (-3115 2875);
FORCEPROP 2 LAST PAGE_BORDER TRUE
J 0
(-3115 2875);
DISPLAY 0.638298 (-3115 2875);
PAINT PINK (-3115 2875);
DISPLAY INVISIBLE (-3115 2875);
FORCEPROP 2 LAST CDS_LIB pure_quanta
J 0
(4775 -2375);
DISPLAY INVISIBLE (4775 -2375);
FORCEPROP 1 LAST CDS_LMAN_SYM_OUTLINE -9475,6775,100,-125
J 0
(4775 -2375);
DISPLAY 0.468085 (4775 -2375);
PAINT GREEN (4775 -2375);
DISPLAY INVISIBLE (4775 -2375);
FORCEPROP 1 LAST COMMENT_BODY TRUE
J 0
(4787 -2388);
DISPLAY 0.978723 (4787 -2388);
PAINT PEACH (4787 -2388);
DISPLAY INVISIBLE (4787 -2388);
FORCEADD DNS..2
(475 -1375);
PAINT RED (475 -1375);
FORCEPROP 2 LAST CDS_LIB mstr_misc
J 0
(475 -1375);
DISPLAY INVISIBLE (475 -1375);
FORCEPROP 1 LAST COMMENT_BODY TRUE
R 1
J 0
(550 -1600);
DISPLAY 0.872340 (550 -1600);
PAINT PEACH (550 -1600);
DISPLAY INVISIBLE (550 -1600);
WIRE 16 -1 (3100 1500)(3100 1450);
WIRE 16 -1 (3275 650)(3275 750);
WIRE 16 -1 (3300 -1050)(3300 -950);
WIRE 16 -1 (3125 -200)(3125 -250);
WIRE 16 -1 (1775 -1600)(1775 -1550);
WIRE 16 -1 (1250 -1525)(1250 -1475);
WIRE 16 -1 (475 -1250)(475 -1300);
WIRE 16 -1 (2950 100)(2950 50);
WIRE 16 -1 (2925 1800)(2925 1750);
WIRE 16 -1 (3275 750)(2725 750);
WIRE 16 -1 (3300 -950)(2750 -950);
WIRE 16 -1 (3125 0)(3125 50);
WIRE 16 -1 (2950 -350)(2750 -350);
WIRE 16 -1 (3125 50)(2950 50);
WIRE 16 -1 (2950 50)(2950 -350);
WIRE 16 -1 (4275 -500)(2750 -500);
FORCEPROP 2 LAST SIG_NAME SPI_PCH_MUXED_IO2
J 0
(2915 -490);
DISPLAY 0.808511 (2915 -490);
WIRE 16 -1 (2750 -600)(4275 -600);
FORCEPROP 2 LAST SIG_NAME SPI_PCH_MUXED_IO1
J 0
(2915 -590);
DISPLAY 0.808511 (2915 -590);
WIRE 16 -1 (2750 -700)(4275 -700);
FORCEPROP 2 LAST SIG_NAME SPI_PCH_MUXED_CS0_N
J 0
(2915 -690);
DISPLAY 0.808511 (2915 -690);
WIRE 16 -1 (2725 1000)(4250 1000);
FORCEPROP 2 LAST SIG_NAME SPI_PCH_MUXED_CLK
J 0
(2865 1010);
DISPLAY 0.808511 (2865 1010);
WIRE 16 -1 (2725 1100)(4250 1100);
FORCEPROP 2 LAST SIG_NAME SPI_PCH_MUXED_IO3
J 0
(2865 1110);
DISPLAY 0.808511 (2865 1110);
WIRE 16 -1 (4250 1200)(2725 1200);
FORCEPROP 2 LAST SIG_NAME SPI_PCH_MUXED_IO0
J 0
(2865 1210);
DISPLAY 0.808511 (2865 1210);
WIRE 16 -1 (425 1250)(1925 1250);
FORCEPROP 2 LAST SIG_NAME SPI_BMC_BIOS_ROM_R_IO3
J 0
(465 1260);
DISPLAY 0.808511 (465 1260);
WIRE 16 -1 (1925 1350)(425 1350);
FORCEPROP 2 LAST SIG_NAME SPI_SYS_MUX_MOSI
J 0
(465 1360);
DISPLAY 0.808511 (465 1360);
WIRE 16 -1 (1925 1400)(425 1400);
FORCEPROP 2 LAST SIG_NAME SPI_BMC_BIOS_ROM_R_MOSI
J 0
(465 1410);
DISPLAY 0.808511 (465 1410);
WIRE 16 -1 (-2500 1600)(-1225 1600);
FORCEPROP 2 LAST SIG_NAME SPI_SYS_MUX_MISO
J 2
(-1250 1610);
DISPLAY 0.808511 (-1250 1610);
WIRE 16 -1 (-2500 1650)(-1225 1650);
FORCEPROP 2 LAST SIG_NAME SPI_SYS_MUX_MOSI
J 2
(-1250 1660);
DISPLAY 0.808511 (-1250 1660);
WIRE 16 -1 (-2500 1700)(-1225 1700);
FORCEPROP 2 LAST SIG_NAME SPI_SYS_MUX_CLK
J 2
(-1250 1710);
DISPLAY 0.808511 (-1250 1710);
WIRE 16 -1 (-4000 2300)(-2725 2300);
FORCEPROP 2 LAST SIG_NAME SPI_BMC_BIOS_CS0_N
J 0
(-3835 2310);
DISPLAY 0.808511 (-3835 2310);
WIRE 16 -1 (-4000 1700)(-2700 1700);
FORCEPROP 2 LAST SIG_NAME SPI_SYS_R_CLK
J 0
(-3825 1710);
DISPLAY 0.808511 (-3825 1710);
WIRE 16 -1 (-4000 2475)(-2725 2475);
FORCEPROP 2 LAST SIG_NAME SPI_BMC_BIOS_ROM_IO3
J 0
(-3825 2485);
DISPLAY 0.808511 (-3825 2485);
WIRE 16 -1 (-4000 2525)(-2725 2525);
FORCEPROP 2 LAST SIG_NAME SPI_BMC_BIOS_ROM_IO2
J 0
(-3825 2535);
DISPLAY 0.808511 (-3825 2535);
WIRE 16 -1 (-4000 2575)(-2725 2575);
FORCEPROP 2 LAST SIG_NAME SPI_BMC_BIOS_ROM_MISO
J 0
(-3825 2585);
DISPLAY 0.808511 (-3825 2585);
WIRE 16 -1 (-4000 2625)(-2725 2625);
FORCEPROP 2 LAST SIG_NAME SPI_BMC_BIOS_ROM_MOSI
J 0
(-3825 2635);
DISPLAY 0.808511 (-3825 2635);
WIRE 16 -1 (3100 1700)(3100 1750);
WIRE 16 -1 (2925 1350)(2725 1350);
WIRE 16 -1 (3100 1750)(2925 1750);
WIRE 16 -1 (2925 1750)(2925 1350);
WIRE 16 -1 (-4000 1650)(-2700 1650);
FORCEPROP 2 LAST SIG_NAME SPI_SYS_R_MOSI
J 0
(-3825 1660);
DISPLAY 0.808511 (-3825 1660);
WIRE 16 -1 (-4000 1600)(-2700 1600);
FORCEPROP 2 LAST SIG_NAME SPI_SYS_R_MISO
J 0
(-3835 1610);
DISPLAY 0.808511 (-3835 1610);
WIRE 16 -1 (-4000 1550)(-2700 1550);
FORCEPROP 2 LAST SIG_NAME SPI_SYS_WP_R_IO2
J 0
(-3825 1560);
DISPLAY 0.808511 (-3825 1560);
WIRE 16 -1 (-4000 1500)(-2700 1500);
FORCEPROP 2 LAST SIG_NAME SPI_SYS_HOLD_R_IO3
J 0
(-3825 1510);
DISPLAY 0.808511 (-3825 1510);
WIRE 16 -1 (-4000 1450)(-2700 1450);
FORCEPROP 2 LAST SIG_NAME SPI_SYS_CS0_N
J 0
(-3835 1460);
DISPLAY 0.808511 (-3835 1460);
WIRE 16 -1 (-2325 -125)(-700 -125);
FORCEPROP 2 LAST SIG_NAME SPI_TPM_CS_R_N
J 2
(-950 -115);
DISPLAY 0.808511 (-950 -115);
WIRE 16 -1 (-2325 225)(-700 225);
FORCEPROP 2 LAST SIG_NAME FM_BMC_BIOS_MUX_CS_SPI_R_SEL_0
J 2
(-810 235);
DISPLAY 0.808511 (-810 235);
WIRE 16 -1 (1925 750)(-250 750);
FORCEPROP 2 LAST SIG_NAME FM_BMC_BIOS_MUX_CS_SPI_R_SEL_0
J 0
(-185 760);
DISPLAY 0.808511 (-185 760);
WIRE 16 -1 (-250 650)(1925 650);
FORCEPROP 2 LAST SIG_NAME PD_BIOS_MUX_EN_N
J 0
(-185 660);
DISPLAY 0.808511 (-185 660);
WIRE 16 -1 (1775 -950)(-225 -950);
FORCEPROP 2 LAST SIG_NAME FM_BMC_BIOS_MUX_CS_SPI_R_SEL_0
J 0
(-60 -940);
DISPLAY 0.808511 (-60 -940);
WIRE 16 -1 (1775 -1350)(1775 -950);
WIRE 16 -1 (1950 -950)(1775 -950);
WIRE 16 -1 (475 -1500)(475 -1625);
WIRE 16 -1 (475 -1625)(650 -1625);
WIRE 16 -1 (650 -1625)(650 -1050);
WIRE 16 -1 (-225 -1050)(650 -1050);
WIRE 16 -1 (1250 -1050)(650 -1050);
FORCEPROP 2 LAST SIG_NAME PD_BIOS_MUX_EN_N
J 0
(-60 -1040);
DISPLAY 0.808511 (-60 -1040);
WIRE 16 -1 (1250 -1050)(1250 -1275);
WIRE 16 -1 (1250 -1050)(1950 -1050);
WIRE 16 -1 (1950 -800)(1200 -800);
FORCEPROP 2 LAST SIG_NAME TP_BIOS_MUX1_PIN14
J 0
(1215 -790);
DISPLAY 0.808511 (1215 -790);
PAINT WHITE (1215 -790);
WIRE 16 -1 (1950 -650)(450 -650);
FORCEPROP 2 LAST SIG_NAME SPI_PCH_SECURE_CS0_N
J 0
(490 -640);
DISPLAY 0.808511 (490 -640);
WIRE 16 -1 (1950 -600)(450 -600);
FORCEPROP 2 LAST SIG_NAME SPI_BMC_BIOS_SOURCE_CS0_N
J 0
(490 -590);
DISPLAY 0.808511 (490 -590);
WIRE 16 -1 (1950 -500)(450 -500);
FORCEPROP 2 LAST SIG_NAME SPI_SYS_MUX_MISO
J 0
(490 -490);
DISPLAY 0.808511 (490 -490);
WIRE 16 -1 (1950 -450)(450 -450);
FORCEPROP 2 LAST SIG_NAME SPI_BMC_BIOS_ROM_R_MISO
J 0
(490 -440);
DISPLAY 0.808511 (490 -440);
WIRE 16 -1 (1950 -350)(450 -350);
FORCEPROP 2 LAST SIG_NAME SPI_SYS_MUX_WP_IO2
J 0
(490 -340);
DISPLAY 0.808511 (490 -340);
WIRE 16 -1 (-1225 1450)(-2500 1450);
FORCEPROP 2 LAST SIG_NAME SPI_PCH_SECURE_CS0_N
J 2
(-1250 1460);
DISPLAY 0.808511 (-1250 1460);
WIRE 16 -1 (1250 950)(1925 950);
FORCEPROP 2 LAST SIG_NAME TP_BIOS_MUX0_PIN13
J 0
(1240 960);
DISPLAY 0.808511 (1240 960);
PAINT WHITE (1240 960);
WIRE 16 -1 (1250 900)(1925 900);
FORCEPROP 2 LAST SIG_NAME TP_BIOS_MUX0_PIN14
J 0
(1240 910);
DISPLAY 0.808511 (1240 910);
PAINT WHITE (1240 910);
WIRE 16 -1 (-2500 1500)(-1225 1500);
FORCEPROP 2 LAST SIG_NAME SPI_SYS_MUX_HOLD_IO3
J 2
(-1250 1510);
DISPLAY 0.808511 (-1250 1510);
WIRE 16 -1 (-2500 1550)(-1225 1550);
FORCEPROP 2 LAST SIG_NAME SPI_SYS_MUX_WP_IO2
J 2
(-1250 1560);
DISPLAY 0.808511 (-1250 1560);
WIRE 16 -1 (-1250 2300)(-2525 2300);
FORCEPROP 2 LAST SIG_NAME SPI_BMC_BIOS_SOURCE_CS0_N
J 0
(-2210 2310);
DISPLAY 0.808511 (-2210 2310);
WIRE 16 -1 (-2525 2475)(-1250 2475);
FORCEPROP 2 LAST SIG_NAME SPI_BMC_BIOS_ROM_R_IO3
J 2
(-1285 2485);
DISPLAY 0.808511 (-1285 2485);
WIRE 16 -1 (-2525 2525)(-1250 2525);
FORCEPROP 2 LAST SIG_NAME SPI_BMC_BIOS_ROM_R_IO2
J 2
(-1285 2535);
DISPLAY 0.808511 (-1285 2535);
WIRE 16 -1 (-2525 2575)(-1250 2575);
FORCEPROP 2 LAST SIG_NAME SPI_BMC_BIOS_ROM_R_MISO
J 2
(-1285 2585);
DISPLAY 0.808511 (-1285 2585);
WIRE 16 -1 (-2525 2625)(-1250 2625);
FORCEPROP 2 LAST SIG_NAME SPI_BMC_BIOS_ROM_R_MOSI
J 2
(-1285 2635);
DISPLAY 0.808511 (-1285 2635);
WIRE 16 -1 (-2525 2675)(-1250 2675);
FORCEPROP 2 LAST SIG_NAME SPI_BMC_BIOS_ROM_R_CLK
J 2
(-1285 2685);
DISPLAY 0.808511 (-1285 2685);
WIRE 16 -1 (-4000 2675)(-2725 2675);
FORCEPROP 2 LAST SIG_NAME SPI_BMC_BIOS_ROM_CLK
J 0
(-3825 2685);
DISPLAY 0.808511 (-3825 2685);
WIRE 16 -1 (-2525 225)(-4050 225);
FORCEPROP 2 LAST SIG_NAME FM_BMC_MUX_CS_SPI_SEL_0
J 0
(-3960 235);
DISPLAY 0.808511 (-3960 235);
WIRE 16 -1 (-2525 -125)(-4050 -125);
FORCEPROP 2 LAST SIG_NAME SPI_TPM_CS_N
J 0
(-3935 -115);
DISPLAY 0.808511 (-3935 -115);
WIRE 16 -1 (2725 900)(3400 900);
FORCEPROP 2 LAST SIG_NAME TP_BIOS_MUX0_PIN12
J 0
(2715 910);
DISPLAY 0.808511 (2715 910);
PAINT WHITE (2715 910);
WIRE 16 -1 (1925 1200)(425 1200);
FORCEPROP 2 LAST SIG_NAME SPI_SYS_MUX_HOLD_IO3
J 0
(465 1210);
DISPLAY 0.808511 (465 1210);
WIRE 16 -1 (1950 -750)(1200 -750);
FORCEPROP 2 LAST SIG_NAME TP_BIOS_MUX1_PIN13
J 0
(1215 -740);
DISPLAY 0.808511 (1215 -740);
PAINT WHITE (1215 -740);
WIRE 16 -1 (1925 1100)(425 1100);
FORCEPROP 2 LAST SIG_NAME SPI_BMC_BIOS_ROM_R_CLK
J 0
(465 1110);
DISPLAY 0.808511 (465 1110);
WIRE 16 -1 (1925 1050)(425 1050);
FORCEPROP 2 LAST SIG_NAME SPI_SYS_MUX_CLK
J 0
(465 1060);
DISPLAY 0.808511 (465 1060);
WIRE 16 -1 (2750 -800)(3425 -800);
FORCEPROP 2 LAST SIG_NAME TP_BIOS_MUX1_PIN12
J 0
(2740 -790);
DISPLAY 0.808511 (2740 -790);
PAINT WHITE (2740 -790);
WIRE 16 -1 (1950 -300)(450 -300);
FORCEPROP 2 LAST SIG_NAME SPI_BMC_BIOS_ROM_R_IO2
J 0
(490 -290);
DISPLAY 0.808511 (490 -290);
DOT 1 (2950 50);
DOT 1 (2925 1750);
DOT 1 (1775 -950);
DOT 1 (1250 -1050);
DOT 1 (650 -1050);
FORCENOTE
TO BIOS MUX
(-1850 1775) 0;
DISPLAY LEFT (-1850 1775);
DISPLAY 1.595745 (-1850 1775);
PAINT WHITE (-1850 1775);
FORCENOTE
FROM PCH
(-4475 1825) 0;
DISPLAY LEFT (-4475 1825);
DISPLAY 1.595745 (-4475 1825);
PAINT WHITE (-4475 1825);
FORCENOTE
TO BIOS MUX
(-925 400) 0;
DISPLAY LEFT (-925 400);
DISPLAY 1.595745 (-925 400);
PAINT WHITE (-925 400);
FORCENOTE
TO TPM
(-925 -50) 0;
DISPLAY LEFT (-925 -50);
DISPLAY 1.595745 (-925 -50);
PAINT WHITE (-925 -50);
FORCENOTE
FROM PCH
(-4525 -50) 0;
DISPLAY LEFT (-4525 -50);
DISPLAY 1.595745 (-4525 -50);
PAINT WHITE (-4525 -50);
FORCENOTE
FROM BMC
(-4525 300) 0;
DISPLAY LEFT (-4525 300);
DISPLAY 1.595745 (-4525 300);
PAINT WHITE (-4525 300);
FORCENOTE
FROM BMC
(-4475 2850) 0;
DISPLAY LEFT (-4475 2850);
DISPLAY 1.595745 (-4475 2850);
PAINT WHITE (-4475 2850);
FORCENOTE
TO BIOS MUX
(-1875 2850) 0;
DISPLAY LEFT (-1875 2850);
DISPLAY 1.595745 (-1875 2850);
PAINT WHITE (-1875 2850);
FORCENOTE
$CDS_IMAGE|clipboard_0_0.jpg|2806|1118
(-3025 3575) 0;
DISPLAY LEFT (-3025 3575);
QUIT
